G04 ================== begin FILE IDENTIFICATION RECORD ==================*
G04 Layout Name:  9051_F0T_Panel_BD_Front_D_v02_20221209_1310.brd*
G04 Film Name:    bot.art*
G04 File Format:  Gerber RS274X*
G04 File Origin:  Cadence Allegro 17.2-S081*
G04 Origin Date:  Mon Dec 12 15:51:17 2022*
G04 *
G04 Layer:  DRAWING FORMAT/TITLE_BLOCK_A*
G04 Layer:  PIN/SPECIAL_DRILL*
G04 Layer:  DRAWING FORMAT/TITLE_BLOCK*
G04 Layer:  VIA CLASS/BOTTOM*
G04 Layer:  PIN/BOTTOM*
G04 Layer:  MANUFACTURING/PHOTOPLOT_OUTLINE*
G04 Layer:  ETCH/BOTTOM*
G04 Layer:  DRAWING FORMAT/TITLE_DATA_BOT*
G04 *
G04 Offset:    (0.00 0.00)*
G04 Mirror:    No*
G04 Mode:      Positive*
G04 Rotation:  0*
G04 FullContactRelief:  No*
G04 UndefLineWidth:     6.00*
G04 ================== end FILE IDENTIFICATION RECORD ====================*
%FSLAX25Y25*MOIN*%
%IR0*IPPOS*OFA0.00000B0.00000*MIA0B0*SFA1.00000B1.00000*%
%ADD22O,.052X.103*%
%ADD11C,.02*%
%ADD13C,.03*%
%ADD27C,.041*%
%ADD21C,.042*%
%ADD20C,.052*%
%ADD23C,.044*%
%ADD14C,.026*%
%ADD18C,.054*%
%ADD15C,.048*%
%ADD26C,.085*%
%ADD25R,.044X.044*%
%ADD19R,.054X.054*%
%ADD28C,.0395*%
%ADD12R,.048X.048*%
%ADD29C,.0785*%
%ADD24O,.052X.075*%
%ADD10C,.125*%
%ADD17C,.119*%
%ADD16C,.158*%
%ADD30C,.006*%
%ADD31C,.0074*%
%ADD39O,.06202X.11302*%
%ADD35C,.03004*%
%ADD40C,.05404*%
%ADD34C,.03604*%
%ADD32C,.06404*%
%ADD33C,.05804*%
%ADD37C,.08607*%
%ADD38C,.16506*%
%ADD36C,.1982*%
G75*
%LPD*%
G75*
G36*
G01X3997Y34898D02*
Y7874D01*
G03X7874Y3997I3877J0D01*
G01X79181D01*
X107180D01*
Y3998D01*
X107181Y3997D01*
X146850D01*
G03X150727Y7874I0J3877D01*
G01Y32747D01*
G02X150786Y32889I200J0D01*
G01X151537Y33640D01*
G02X151679Y33699I142J-141D01*
G01X152524D01*
G02X152724Y33499I0J-200D01*
G01Y7874D01*
G02X146850Y2000I-5874J0D01*
G01X7874D01*
G02X2000Y7874I0J5874D01*
G01Y34898D01*
X3997D01*
G37*
G36*
G01X67141Y291500D02*
X96728D01*
G02X96870Y291441I0J-200D01*
G01X97941Y290370D01*
G02X98000Y290228I-141J-142D01*
G01Y281083D01*
G02X97941Y280941I-200J0D01*
G01X91059Y274059D01*
G03X91000Y273917I141J-142D01*
G01Y266083D01*
G03X91059Y265941I200J0D01*
G01X97941Y259059D01*
G02X98000Y258917I-141J-142D01*
G01Y174583D01*
G03X98059Y174441I200J0D01*
G01X116441Y156059D01*
G02X116500Y155917I-141J-142D01*
G01Y145583D01*
G02X116441Y145441I-200J0D01*
G01X115559Y144559D01*
G02X115417Y144500I-142J141D01*
G01X83083D01*
G03X82941Y144441I0J-200D01*
G01X79829Y141329D01*
G02X79687Y141270I-142J141D01*
G01X56853D01*
G03X56711Y141211I0J-200D01*
G01X50957Y135457D01*
G03X50898Y135315I141J-142D01*
G01Y128527D01*
G03X50957Y128385I200J0D01*
G01X56536Y122806D01*
G02X56595Y122664I-141J-142D01*
G01Y93299D01*
G03X56654Y93157I200J0D01*
G01X60219Y89592D01*
G02X60278Y89450I-141J-142D01*
G01Y57169D01*
G02X60207Y57016I-200J0D01*
G01X59938Y56790D01*
X59854Y56767D01*
X59809Y56775D01*
G03X59500Y56802I-311J-1775D01*
G03Y53198I0J-1802D01*
G03X60895Y53860I0J1801D01*
G01X60922Y53892D01*
X60995Y53930D01*
X61369Y53956D01*
X61447Y53928D01*
X61477Y53900D01*
G03X62500Y53498I1023J1101D01*
G03X63159Y53650I1J1502D01*
G01X63217Y53679D01*
X63342Y53658D01*
X66957Y50043D01*
G03X67099Y49984I142J141D01*
G01X74100D01*
G02X74242Y49925I0J-200D01*
G01X76050Y48117D01*
G02X76108Y47976I-142J-141D01*
G01Y31191D01*
G02X76050Y31050I-200J0D01*
G01X73932Y28932D01*
G03X73873Y28790I141J-142D01*
G01Y7481D01*
G02X73814Y7339I-200J0D01*
G01X71913Y5438D01*
G02X71771Y5379I-142J141D01*
G01X13376D01*
X13358Y5396D01*
X7679D01*
G02X7537Y5455I0J200D01*
G01X6359Y6633D01*
G02X6300Y6775I141J142D01*
G01Y22255D01*
G02X6359Y22397I200J0D01*
G01X6611Y22649D01*
G02X6753Y22708I142J-141D01*
G01X15681D01*
G02X15823Y22649I0J-200D01*
G01X17210Y21262D01*
G02X17269Y21120I-141J-142D01*
G01Y16305D01*
G03X17328Y16163I200J0D01*
G01X18092Y15399D01*
G03X18234Y15340I142J141D01*
G01X22218D01*
G03X22360Y15399I0J200D01*
G01X23643Y16682D01*
G03X23702Y16824I-141J142D01*
G01Y19864D01*
G02X23825Y20049I200J0D01*
G01X28703Y22070D01*
G02X28779Y22085I76J-185D01*
G01X36273D01*
G03X36415Y22144I0J200D01*
G01X41744Y27473D01*
X41781Y27488D01*
G03X42225Y27785I-526J1267D01*
G01X47470Y33030D01*
G03X47767Y33474I-970J970D01*
G01X47782Y33511D01*
X48481Y34210D01*
G03X48540Y34352I-141J142D01*
G01Y82877D01*
G03X48481Y83019I-200J0D01*
G01X37559Y93941D01*
G03X37417Y94000I-142J-141D01*
G01X26373D01*
X26363Y94001D01*
G03X24183Y94128I-2350J-21560D01*
G01X24182D01*
G03X23953Y94129I-209J-21686D01*
G01X23912Y94130D01*
X23841Y94159D01*
X21240Y96760D01*
G02X21181Y96902I141J142D01*
G01Y159098D01*
G02X21240Y159240I200J0D01*
G01X36941Y174941D01*
G02X37083Y175000I142J-141D01*
G01X72293D01*
G03X72435Y175059I0J200D01*
G01X84441Y187065D01*
G03X84500Y187207I-141J142D01*
G01Y236417D01*
G03X84441Y236559I-200J0D01*
G01X78809Y242191D01*
G02X78750Y242333I141J142D01*
G01Y257667D01*
G03X78691Y257809I-200J0D01*
G01X77610Y258890D01*
X77601Y258901D01*
G03X77301Y259201I-1201J-901D01*
G01X77290Y259210D01*
X76059Y260441D01*
G03X75917Y260500I-142J-141D01*
G01X69083D01*
G03X68941Y260441I0J-200D01*
G01X68059Y259559D01*
G03X68000Y259417I141J-142D01*
G01Y257583D01*
G02X67941Y257441I-200J0D01*
G01X67059Y256559D01*
G02X66917Y256500I-142J141D01*
G01X61583D01*
G02X61441Y256559I0J200D01*
G01X60559Y257441D01*
G02X60500Y257583I141J142D01*
G01Y284917D01*
G02X60559Y285059I200J0D01*
G01X62912Y287412D01*
G02X63072Y287470I142J-141D01*
G01X63423Y287438D01*
X63500Y287393D01*
X63525Y287356D01*
G03X64764Y286703I1239J849D01*
G03X66266Y288205I0J1502D01*
G03X65613Y289444I-1502J0D01*
G01X65576Y289469D01*
X65531Y289546D01*
X65499Y289897D01*
G02X65557Y290057I199J18D01*
G01X66712Y291212D01*
X66724Y291221D01*
G03X67010Y291450I-2543J3470D01*
G02X67141Y291500I132J-150D01*
G37*
G36*
G01X4331Y72441D02*
G02X43701I19685J0D01*
G01Y58661D01*
G02X4331I-19685J0D01*
G01Y72441D01*
G37*
G36*
G01X4041Y273000D02*
G03X3997Y272418I3834J-582D01*
G01Y83630D01*
X2000D01*
Y272419D01*
G02X2029Y273000I5875J-2D01*
G01X4041D01*
G37*
G36*
G01X50583Y312000D02*
X120917D01*
G02X121059Y311941I0J-200D01*
G01X123441Y309559D01*
G02X123500Y309417I-141J-142D01*
G01Y286583D01*
G02X123441Y286441I-200J0D01*
G01X108810Y271810D01*
G02X108676Y271751I-142J141D01*
G01X108365Y271740D01*
X108295Y271765D01*
X108266Y271790D01*
G03X107284Y272155I-982J-1137D01*
G03X105782Y270653I0J-1502D01*
G03X106857Y269213I1502J0D01*
G01X106921Y269194D01*
X107000Y269089D01*
Y238583D01*
G03X107059Y238441I200J0D01*
G01X126441Y219059D01*
G02X126500Y218917I-141J-142D01*
G01Y187583D01*
G03X126559Y187441I200J0D01*
G01X149480Y164520D01*
G02X149539Y164378I-141J-142D01*
G01Y138291D01*
G02X149454Y138128I-200J1D01*
G01X149146Y137911D01*
X149051Y137898D01*
X149005Y137915D01*
G03X148500Y138002I-504J-1415D01*
G03Y134998I0J-1502D01*
G03X149005Y135085I1J1502D01*
G01X149051Y135102D01*
X149146Y135089D01*
X149454Y134872D01*
G02X149539Y134709I-115J-164D01*
G01Y134596D01*
G02X149440Y134423I-200J0D01*
G01X149336Y134362D01*
G02X149149Y134355I-100J173D01*
G03X148500Y134502I-648J-1355D01*
G03Y131498I0J-1502D01*
G03X149005Y131585I1J1502D01*
G01X149051Y131602D01*
X149146Y131589D01*
X149454Y131372D01*
G02X149539Y131209I-115J-164D01*
G01Y131096D01*
G02X149440Y130923I-200J0D01*
G01X149336Y130862D01*
G02X149149Y130855I-100J173D01*
G03X148500Y131002I-648J-1355D01*
G03Y127998I0J-1502D01*
G03X149005Y128085I1J1502D01*
G01X149051Y128102D01*
X149146Y128089D01*
X149454Y127872D01*
G02X149539Y127709I-115J-164D01*
G01Y127596D01*
G02X149440Y127423I-200J0D01*
G01X149336Y127362D01*
G02X149149Y127355I-100J173D01*
G03X148500Y127502I-648J-1355D01*
G03Y124498I0J-1502D01*
G03X149005Y124585I1J1502D01*
G01X149051Y124602D01*
X149146Y124589D01*
X149454Y124372D01*
G02X149539Y124209I-115J-164D01*
G01Y124096D01*
G02X149440Y123923I-200J0D01*
G01X149336Y123862D01*
G02X149149Y123855I-100J173D01*
G03X148500Y124002I-648J-1355D01*
G03Y120998I0J-1502D01*
G03X149005Y121085I1J1502D01*
G01X149051Y121102D01*
X149146Y121089D01*
X149454Y120872D01*
G02X149539Y120709I-115J-164D01*
G01Y120596D01*
G02X149440Y120423I-200J0D01*
G01X149336Y120362D01*
G02X149149Y120355I-100J173D01*
G03X148500Y120502I-648J-1355D01*
G03Y117498I0J-1502D01*
G03X149005Y117585I1J1502D01*
G01X149051Y117602D01*
X149146Y117589D01*
X149454Y117372D01*
G02X149539Y117209I-115J-164D01*
G01Y117096D01*
G02X149440Y116923I-200J0D01*
G01X149336Y116862D01*
G02X149149Y116855I-100J173D01*
G03X148500Y117002I-648J-1355D01*
G03Y113998I0J-1502D01*
G03X149005Y114085I1J1502D01*
G01X149051Y114102D01*
X149146Y114089D01*
X149454Y113872D01*
G02X149539Y113709I-115J-164D01*
G01Y113596D01*
G02X149440Y113423I-200J0D01*
G01X149336Y113362D01*
G02X149149Y113355I-100J173D01*
G03X148500Y113502I-648J-1355D01*
G03Y110498I0J-1502D01*
G03X149005Y110585I1J1502D01*
G01X149051Y110602D01*
X149146Y110589D01*
X149454Y110372D01*
G02X149539Y110209I-115J-164D01*
G01Y105791D01*
G02X149454Y105628I-200J1D01*
G01X149146Y105411D01*
X149051Y105398D01*
X149005Y105415D01*
G03X148500Y105502I-504J-1415D01*
G03Y102498I0J-1502D01*
G03X149005Y102585I1J1502D01*
G01X149051Y102602D01*
X149146Y102589D01*
X149454Y102372D01*
G02X149539Y102209I-115J-164D01*
G01Y97791D01*
G02X149454Y97628I-200J1D01*
G01X149146Y97411D01*
X149051Y97398D01*
X149005Y97415D01*
G03X148500Y97502I-504J-1415D01*
G03Y94498I0J-1502D01*
G03X149005Y94585I1J1502D01*
G01X149051Y94602D01*
X149146Y94589D01*
X149454Y94372D01*
G02X149539Y94209I-115J-164D01*
G01Y89791D01*
G02X149454Y89628I-200J1D01*
G01X149146Y89411D01*
X149051Y89398D01*
X149005Y89415D01*
G03X148500Y89502I-504J-1415D01*
G03Y86498I0J-1502D01*
G03X149005Y86585I1J1502D01*
G01X149051Y86602D01*
X149146Y86589D01*
X149454Y86372D01*
G02X149539Y86209I-115J-164D01*
G01Y81791D01*
G02X149454Y81628I-200J1D01*
G01X149146Y81411D01*
X149051Y81398D01*
X149005Y81415D01*
G03X148500Y81502I-504J-1415D01*
G03Y78498I0J-1502D01*
G03X149005Y78585I1J1502D01*
G01X149051Y78602D01*
X149146Y78589D01*
X149454Y78372D01*
G02X149539Y78209I-115J-164D01*
G01Y75642D01*
G02X149480Y75500I-200J0D01*
G01X148091Y74111D01*
G02X147949Y74052I-142J141D01*
G01X132135D01*
G03X131993Y73993I0J-200D01*
G01X131193Y73193D01*
X131154Y73169D01*
X131130Y73162D01*
G03X120264Y62295I5091J-15957D01*
G01X120256Y62272D01*
X120232Y62232D01*
X120185Y62185D01*
G03X120126Y62043I141J-142D01*
G01Y61841D01*
X120118Y61814D01*
G03X119472Y57205I16103J-4607D01*
G01Y43425D01*
G03X120118Y38815I16749J-3D01*
G01X120126Y38788D01*
Y36617D01*
G03X120185Y36475I200J0D01*
G01X121867Y34793D01*
X121880Y34772D01*
G03X125507Y30550I14342J8652D01*
G02X125579Y30397I-128J-154D01*
G01Y26143D01*
G02X125520Y26001I-200J0D01*
G01X124275Y24756D01*
G02X124133Y24697I-142J141D01*
G01X119277D01*
G02X119135Y24756I0J200D01*
G01X114734Y29157D01*
G02X114675Y29299I141J142D01*
G01Y30634D01*
G02X114706Y30741I200J0D01*
G03Y32661I-1525J960D01*
G02X114675Y32768I169J107D01*
G01Y69725D01*
G02X114734Y69866I200J-1D01*
G01X126752Y81884D01*
G02X126893Y81943I142J-141D01*
G01X126905D01*
X127248Y82286D01*
G02X127390Y82345I142J-141D01*
G01X136569D01*
G03X136711Y82404I0J200D01*
G01X137325Y83018D01*
X137370Y83044D01*
X137395Y83051D01*
G03X138449Y84105I-395J1449D01*
G01X138456Y84130D01*
X138482Y84175D01*
X138941Y84634D01*
G03X139000Y84776I-141J142D01*
G01Y137417D01*
G03X138941Y137559I-200J0D01*
G01X137559Y138941D01*
G03X137417Y139000I-142J-141D01*
G01X120583D01*
G03X120441Y138941I0J-200D01*
G01X118559Y137059D01*
G03X118500Y136917I141J-142D01*
G01Y134083D01*
G02X118441Y133941I-200J0D01*
G01X98059Y113559D01*
G02X97917Y113500I-142J141D01*
G01X90083D01*
G03X89941Y113441I0J-200D01*
G01X88559Y112059D01*
G03X88500Y111917I141J-142D01*
G01Y101583D01*
G02X88441Y101441I-200J0D01*
G01X85059Y98059D01*
G02X84917Y98000I-142J141D01*
G01X80083D01*
G03X79941Y97941I0J-200D01*
G01X78559Y96559D01*
G03X78500Y96417I141J-142D01*
G01Y85583D01*
G02X78441Y85441I-200J0D01*
G01X77559Y84559D01*
G02X77417Y84500I-142J141D01*
G01X73583D01*
G02X73441Y84559I0J200D01*
G01X71559Y86441D01*
G02X71500Y86583I141J142D01*
G01Y88456D01*
G02X71590Y88623I200J0D01*
G01X71912Y88835D01*
X72012Y88844D01*
X72059Y88823D01*
G03X73000Y88628I942J2177D01*
G03X75372Y91000I0J2372D01*
G03X74677Y92677I-2371J0D01*
G01X74636Y92718D01*
G02X74578Y92861I142J141D01*
G01X74581Y93188D01*
X74612Y93261D01*
X74642Y93289D01*
G03X75372Y95000I-1642J1712D01*
G03X74677Y96677I-2371J0D01*
G01X73270Y98084D01*
G02X73212Y98225I142J141D01*
G01Y116629D01*
G02X73270Y116770I200J0D01*
G01X77941Y121441D01*
G02X78083Y121500I142J-141D01*
G01X90417D01*
G03X90559Y121559I0J200D01*
G01X112440Y143440D01*
G02X112581Y143498I141J-142D01*
G01X115915D01*
X115916Y143500D01*
X115917D01*
G03X116059Y143559I0J200D01*
G01X117441Y144941D01*
G03X117500Y145083I-141J142D01*
G01Y145084D01*
X117502Y145085D01*
Y156415D01*
X117500Y156416D01*
Y157417D01*
G03X117441Y157559I-200J0D01*
G01X99559Y175441D01*
G02X99500Y175583I141J142D01*
G01Y259417D01*
G03X99441Y259559I-200J0D01*
G01X95059Y263941D01*
G02X95000Y264083I141J142D01*
G01Y275917D01*
G02X95059Y276059I200J0D01*
G01X99441Y280441D01*
G03X99500Y280583I-141J142D01*
G01Y287008D01*
G02X99633Y287196I200J0D01*
G01X100049Y287344D01*
X100170Y287310D01*
X100211Y287260D01*
G03X101378Y286703I1167J944D01*
G03Y289707I0J1502D01*
G03X100211Y289150I0J-1501D01*
G01X100170Y289100D01*
X100049Y289066D01*
X99633Y289214D01*
G02X99500Y289402I67J188D01*
G01Y290417D01*
G03X99441Y290559I-200J0D01*
G01X97559Y292441D01*
G03X97417Y292500I-142J-141D01*
G01X97227D01*
X97226Y292502D01*
X72581D01*
G02X72440Y292560I0J200D01*
G01X66059Y298941D01*
G03X65917Y299000I-142J-141D01*
G01X62083D01*
G03X61941Y298941I0J-200D01*
G01X59370Y296370D01*
G03X59311Y296228I141J-142D01*
G01Y265444D01*
G02X59202Y265266I-200J0D01*
G01X58834Y265077D01*
X58724Y265086D01*
X58677Y265119D01*
G03X57800Y265402I-877J-1219D01*
G03X56298Y263900I0J-1502D01*
G03X56418Y263312I1501J0D01*
G01X56436Y263270D01*
X56432Y263182D01*
X56247Y262827D01*
X56176Y262773D01*
X56132Y262764D01*
G03X54698Y261000I368J-1764D01*
G03X58302I1802J0D01*
G03X58062Y261899I-1802J0D01*
G01X58039Y261938D01*
X58032Y262026D01*
X58174Y262401D01*
X58237Y262462D01*
X58281Y262477D01*
G03X58677Y262681I-482J1422D01*
G01X58724Y262714D01*
X58834Y262723D01*
X59202Y262534D01*
G02X59311Y262356I-91J-178D01*
G01Y255769D01*
G03X59370Y255627I200J0D01*
G01X61938Y253059D01*
G03X62080Y253000I142J141D01*
G01X66417D01*
G03X66559Y253059I0J200D01*
G01X68941Y255441D01*
G03X69000Y255583I-141J142D01*
G01Y257084D01*
X69002Y257085D01*
Y258919D01*
G02X69060Y259060I200J0D01*
G01X69440Y259440D01*
G02X69581Y259498I141J-142D01*
G01X74419D01*
G02X74560Y259440I0J-200D01*
G01X75046Y258954D01*
G02X75080Y258717I-142J-141D01*
G03X74898Y258000I1321J-717D01*
G03X76400Y256498I1502J0D01*
G03X77117Y256680I0J1503D01*
G01X77176Y256712D01*
X77306Y256694D01*
X77441Y256559D01*
G02X77500Y256417I-141J-142D01*
G01Y242072D01*
G02X77300Y241872I-200J0D01*
G01X76500D01*
G03X74128Y239500I0J-2372D01*
G03X74858Y237789I2372J1D01*
G01X74888Y237760D01*
X74920Y237686D01*
Y237314D01*
X74888Y237240D01*
X74858Y237211D01*
G03X74128Y235500I1642J-1712D01*
G03X76500Y233128I2372J0D01*
G01X76935D01*
G02X77076Y233070I0J-200D01*
G01X77246Y232900D01*
G02X77304Y232759I-142J-141D01*
G01Y229358D01*
G02X77230Y229203I-200J0D01*
G01X76952Y228979D01*
X76864Y228958D01*
X76819Y228968D01*
G03X76500Y229002I-318J-1468D01*
G03Y225998I0J-1502D01*
G03X76819Y226032I1J1502D01*
G01X76864Y226042D01*
X76952Y226021D01*
X77230Y225797D01*
G02X77304Y225642I-126J-155D01*
G01Y199741D01*
G02X77246Y199600I-200J0D01*
G01X64823Y187177D01*
G03X64128Y185500I1676J-1677D01*
G03X64858Y183789I2372J1D01*
G01X64888Y183761D01*
X64919Y183688D01*
X64922Y183361D01*
G02X64864Y183218I-200J-2D01*
G01X64823Y183177D01*
G03X64128Y181500I1676J-1677D01*
G03X66500Y179128I2372J0D01*
G03X67869Y179564I-1J2372D01*
G01X67915Y179596D01*
X68026Y179604D01*
X68392Y179415D01*
G02X68500Y179237I-92J-178D01*
G01Y176583D01*
G02X68441Y176441I-200J0D01*
G01X68060Y176060D01*
G02X67919Y176002I-141J142D01*
G01X36585D01*
X36584Y176000D01*
X36583D01*
G03X36441Y175941I0J-200D01*
G01X20200Y159700D01*
G03X20141Y159558I141J-142D01*
G01Y103224D01*
G02X20082Y103082I-200J0D01*
G01X19059Y102059D01*
G02X18917Y102000I-142J141D01*
G01X6303D01*
G02X6161Y102059I0J200D01*
G01X5279Y102941D01*
G02X5220Y103083I141J142D01*
G01Y230637D01*
G02X5279Y230779I200J0D01*
G01X18658Y244158D01*
X18783Y244179D01*
X18841Y244150D01*
G03X19500Y243998I658J1350D01*
G03X21002Y245500I0J1502D01*
G03X20850Y246159I-1502J1D01*
G01X20821Y246217D01*
X20842Y246342D01*
X45941Y271441D01*
G03X46000Y271583I-141J142D01*
G01Y307417D01*
G02X46059Y307559I200J0D01*
G01X50441Y311941D01*
G02X50583Y312000I142J-141D01*
G37*
G36*
G01X10236Y293229D02*
G02X41732I15748J0D01*
G01Y279449D01*
G02X10236I-15748J0D01*
G01Y293229D01*
G37*
G36*
G01X58464Y337173D02*
X113583D01*
G02X119457Y331299I0J-5874D01*
G01Y322835D01*
G03X129331Y312961I9874J0D01*
G01X142520D01*
G02X148394Y307087I0J-5874D01*
G01Y302701D01*
X147314D01*
X147262Y302753D01*
G03X146437Y303941I-14980J-9522D01*
G01X146417Y303967D01*
X146397Y304028D01*
Y307087D01*
G03X142522Y310963I-3876J0D01*
G01X133037D01*
X133032Y310964D01*
G03X132283Y310979I-730J-17735D01*
G03X131534Y310964I-19J-17750D01*
G01X131529Y310963D01*
X129331D01*
G02X117459Y322835I0J11872D01*
G01Y331299D01*
G03X113583Y335175I-3876J0D01*
G01X58464D01*
G03X54587Y331299I0J-3877D01*
G01Y322833D01*
G02X42716Y310963I-11871J1D01*
G01X12205D01*
G03X8329Y307087I0J-3876D01*
G01Y291218D01*
X6331D01*
Y307087D01*
G02X12205Y312961I5874J0D01*
G01X42716D01*
G03X52590Y322835I0J9874D01*
G01Y331299D01*
G02X58464Y337173I5874J0D01*
G37*
G36*
G01X86583Y26000D02*
X88917D01*
G02X89059Y25941I0J-200D01*
G01X103941Y11059D01*
G02X104000Y10917I-141J-142D01*
G01Y7583D01*
G02X103941Y7441I-200J0D01*
G01X102559Y6059D01*
G02X102417Y6000I-142J141D01*
G01X80083D01*
G02X79941Y6059I0J200D01*
G01X78559Y7441D01*
G02X78500Y7583I141J142D01*
G01Y17917D01*
G02X78559Y18059I200J0D01*
G01X86441Y25941D01*
G02X86583Y26000I142J-141D01*
G37*
G36*
G01X99707Y65500D02*
G03I-707J0D01*
G37*
G36*
G01X122081Y137998D02*
X136919D01*
G02X137060Y137940I0J-200D01*
G01X137940Y137060D01*
G02X137998Y136919I-142J-141D01*
G01Y102081D01*
G02X137940Y101940I-200J0D01*
G01X108059Y72059D01*
G03X108000Y71917I141J-142D01*
G01Y71638D01*
X107994Y71614D01*
G03X107954Y71283I1331J-329D01*
G01Y65036D01*
G02X107895Y64895I-200J1D01*
G01X107683Y64683D01*
X107593Y64653D01*
X107545Y64661D01*
G03X107318Y64678I-225J-1485D01*
G03X106741Y64563I-1J-1502D01*
G01X106704Y64548D01*
X105035D01*
G02X104894Y64606I0J200D01*
G01X104059Y65441D01*
G02X104000Y65583I141J142D01*
G01Y66407D01*
X104024Y66473D01*
X104046Y66500D01*
G03X104671Y68228I-2076J1728D01*
G03X102006Y70930I-2702J0D01*
G01X101967D01*
X101895Y70961D01*
X100928Y71928D01*
X97590Y75267D01*
G02X97531Y75409I141J142D01*
G01Y77735D01*
G03X97472Y77877I-200J0D01*
G01X96761Y78588D01*
X96739Y78566D01*
X93017D01*
G02X92875Y78625I0J200D01*
G01X92077Y79423D01*
G02X92041Y79472I141J142D01*
G03X91619Y80045I-2099J-1104D01*
G01X91559Y80105D01*
G02X91500Y80247I141J142D01*
G01Y110417D01*
G02X91559Y110559I200J0D01*
G01X92413Y111413D01*
G02X92555Y111472I142J-141D01*
G01X99389D01*
G03X99531Y111531I0J200D01*
G01X119658Y131658D01*
X119783Y131679D01*
X119841Y131650D01*
G03X120500Y131498I658J1350D01*
G03X122002Y133000I0J1502D01*
G03X121559Y134065I-1502J0D01*
G02X121500Y134207I141J142D01*
G01Y135293D01*
G02X121559Y135435I200J0D01*
G03X122002Y136500I-1059J1065D01*
G03X121680Y137430I-1502J1D01*
G01X121632Y137490D01*
X121641Y137641D01*
X121940Y137940D01*
G02X122081Y137998I141J-142D01*
G37*
G36*
G01X120473Y57205D02*
G02X151969I15748J0D01*
G01Y43425D01*
G02X120473I-15748J0D01*
G01Y57205D01*
G37*
G36*
G01X109449Y261323D02*
G02X148819I19685J0D01*
G01Y247543D01*
G02X109449I-19685J0D01*
G01Y261323D01*
G37*
G36*
G01X128583Y224500D02*
X148917D01*
G02X149059Y224441I0J-200D01*
G01X149536Y223964D01*
G02X149595Y223822I-141J-142D01*
G01Y176678D01*
G02X149536Y176536I-200J0D01*
G01X148559Y175559D01*
G02X148417Y175500I-142J141D01*
G01X139999D01*
G02X139858Y175559I1J200D01*
G01X127560Y187856D01*
G02X127502Y187998I142J141D01*
G01Y219415D01*
X127500Y219416D01*
Y223417D01*
G02X127559Y223559I200J0D01*
G01X128441Y224441D01*
G02X128583Y224500I142J-141D01*
G37*
G36*
G01X149723Y276143D02*
X151392D01*
G02X152724Y272419I-4543J-3725D01*
G01Y66056D01*
G02X152601Y65872I-200J1D01*
G01X152544Y65849D01*
X152426Y65872D01*
X150785Y67513D01*
G02X150727Y67655I142J141D01*
G01Y189701D01*
Y211701D01*
Y272418D01*
G03X149661Y275088I-3878J0D01*
G02X149599Y275153I8559J8226D01*
G02X149550Y275336I146J137D01*
G03X149723Y276143I-17265J4123D01*
G37*
%LPC*%
G75*
G36*
G01X16765Y285779D02*
G02X35203Y285778I9219J7449D01*
G03X33900Y282093I4560J-3685D01*
G01Y279449D01*
G02X18068I-7916J0D01*
G01Y282093D01*
G03X16765Y285779I-5865J0D01*
G37*
G36*
G01X127002Y49755D02*
G02X145440Y49754I9219J7449D01*
G03X144137Y46069I4560J-3685D01*
G01Y43425D01*
G02X128305I-7916J0D01*
G01Y46069D01*
G03X127002Y49755I-5865J0D01*
G37*
G54D39*
X109095Y89370D03*
G54D35*
X71851Y288205D03*
X75700Y263900D03*
X80119Y288205D03*
X19500Y229500D03*
X128385Y80000D03*
X100197Y270653D03*
X106103Y288205D03*
X133500Y160000D03*
X19500Y237500D03*
X118000Y116500D03*
X120500Y126000D03*
Y129500D03*
G54D40*
X101969Y76102D03*
Y83976D03*
G54D34*
X48941Y89500D03*
X54059Y102500D03*
X59586Y40000D03*
X93111Y288205D03*
X84843D03*
X78937Y270653D03*
X86024D03*
X11500Y192000D03*
X19500Y221500D03*
Y213500D03*
X33000Y186000D03*
X11500Y184000D03*
Y200000D03*
X8000Y110500D03*
X16000Y109441D03*
X59075Y204000D03*
X41000Y213532D03*
X64075Y200000D03*
X68500Y231500D03*
X69075Y247000D03*
G54D32*
X57480Y26299D03*
X67480D03*
G54D33*
X43937Y20079D03*
G54D37*
X107874Y294685D03*
G54D38*
X134016Y147928D03*
G54D36*
X24016Y58661D03*
X129134Y247543D03*
%LPD*%
G75*
G54D10*
X-58189Y19685D03*
Y666535D03*
X14000Y255500D03*
X60989Y131906D03*
X134016Y147928D03*
X372440Y19685D03*
Y666535D03*
G54D20*
X64174Y294685D03*
X107874D03*
G54D11*
X5192Y3841D03*
X10315Y13000D03*
X3004Y90860D03*
Y106468D03*
X16000Y98441D03*
X8000Y103500D03*
Y114500D03*
X3004Y126468D03*
Y146468D03*
Y166468D03*
Y186468D03*
X11500Y196000D03*
Y188000D03*
X3004Y206468D03*
X11500Y204000D03*
X3004Y226468D03*
Y246468D03*
X13984Y279449D03*
X7348Y302588D03*
X7337Y292952D03*
X27028Y3019D03*
X19500Y209500D03*
Y217500D03*
Y229500D03*
Y237500D03*
Y225500D03*
Y233500D03*
Y241500D03*
Y245500D03*
X34469Y270964D03*
X25984Y267449D03*
X17499Y270964D03*
X35701Y311937D03*
X16801Y311946D03*
X46184Y3014D03*
X42400Y86500D03*
X55925Y204000D03*
X57800Y263900D03*
X37984Y279449D03*
X51404Y316245D03*
X53595Y331234D03*
X60867Y3014D03*
X63600Y34192D03*
X64500Y63500D03*
X66925Y70000D03*
X77382Y58000D03*
X62500Y55000D03*
X77453Y77500D03*
X73000Y91000D03*
Y87000D03*
X65000Y73500D03*
X73000Y95000D03*
X78500Y110000D03*
Y112500D03*
X75425Y102000D03*
X66000Y118000D03*
X59500Y117960D03*
X76000Y123000D03*
Y126500D03*
X78340Y136000D03*
X70000Y138500D03*
X70500Y177500D03*
X67000D03*
X66500Y181500D03*
Y185500D03*
Y193500D03*
X76500Y227500D03*
Y239500D03*
Y235500D03*
Y231500D03*
X76400Y258000D03*
X75700Y263900D03*
X64000Y258000D03*
X66500D03*
X65925Y247000D03*
X72500Y258000D03*
X70000D03*
X64764Y288205D03*
X71851D03*
X80119D03*
X68308D03*
X68968Y336145D03*
X80697Y3016D03*
X98502D03*
X99000Y65500D03*
X84500Y76500D03*
X81000Y91000D03*
X84500Y95000D03*
X81000D03*
X81500Y126500D03*
X94500Y129000D03*
X83500Y133000D03*
Y129500D03*
X88500Y123500D03*
X92500Y126000D03*
X80310Y138735D03*
X100197Y270653D03*
X101378Y288205D03*
X96654D03*
X89567D03*
X83076Y336146D03*
X117186Y3014D03*
X122130Y30217D03*
X107318Y63176D03*
X106970Y65827D03*
Y68327D03*
X118000Y116500D03*
X120500Y136500D03*
Y129500D03*
Y133000D03*
Y126000D03*
X112000Y147000D03*
Y150500D03*
X115000Y147000D03*
Y150500D03*
X107284Y270653D03*
X106103Y288205D03*
X118455Y323862D03*
X116870Y334863D03*
X103076Y336146D03*
X136936Y3035D03*
X124221Y43425D03*
X127736Y34940D03*
X136221Y31425D03*
X144706Y34940D03*
X128385Y80000D03*
X137000Y84500D03*
Y88000D03*
Y92000D03*
X134500Y136500D03*
Y133000D03*
Y129500D03*
Y126000D03*
Y122500D03*
X133500Y160000D03*
X129715Y311960D03*
X150330Y4601D03*
X151688Y13776D03*
X148221Y43425D03*
X151706Y72716D03*
X151683Y90942D03*
X148500Y88000D03*
Y80000D03*
Y76000D03*
Y92000D03*
X151684Y112798D03*
X148500Y96000D03*
Y112000D03*
Y104000D03*
Y108000D03*
Y100000D03*
X151684Y132682D03*
X148500Y136500D03*
Y133000D03*
Y129500D03*
Y126000D03*
Y122500D03*
Y119000D03*
Y115500D03*
X151683Y151482D03*
X151705Y172913D03*
X151663Y192669D03*
X151662Y212615D03*
X151704Y232645D03*
X151705Y252655D03*
X144561Y311483D03*
X350990Y434698D03*
X341684Y431703D03*
X339169Y431688D03*
X349698D03*
X352213Y431703D03*
X344419Y428405D03*
X346934Y428420D03*
X352199Y428435D03*
X349684Y428420D03*
X341670Y428405D03*
X339155Y428420D03*
X340461Y434698D03*
X350539Y607802D03*
X351845Y614080D03*
X349330Y614095D03*
X338801Y614065D03*
X341316Y614080D03*
X338787Y610797D03*
X341302Y610812D03*
X344066Y614080D03*
X346581Y614095D03*
X351831Y610812D03*
X349316Y610797D03*
X340010Y607802D03*
X371184Y327889D03*
X368669Y327874D03*
X379198D03*
X373919Y324591D03*
X376434Y324606D03*
X379184D03*
X371170Y324591D03*
X368655Y324606D03*
X369961Y330884D03*
X369510Y607802D03*
X378816Y610797D03*
X370802Y610812D03*
X368287Y610797D03*
X376081Y614095D03*
X373566Y614080D03*
X368301Y614065D03*
X370816Y614080D03*
X378830Y614095D03*
X381713Y327889D03*
X381699Y324621D03*
X380490Y330884D03*
X381331Y610812D03*
X381345Y614080D03*
X380039Y607802D03*
G54D30*
G01X-117168Y-317735D02*
Y-322735D01*
G01X-118625Y-317735D02*
X-115711D01*
G01X-110801Y-322735D02*
X-113335D01*
Y-317735D01*
X-110801D01*
G01X-111815Y-320152D02*
X-113335D01*
G01X-108235Y-317735D02*
Y-322735D01*
X-105701D01*
G01X-101868Y-322902D02*
X-101995Y-322818D01*
Y-322652D01*
X-101868Y-322568D01*
X-101741Y-322652D01*
Y-322818D01*
X-101868Y-322902D01*
G01Y-320652D02*
X-101995Y-320568D01*
Y-320402D01*
X-101868Y-320318D01*
X-101741Y-320402D01*
Y-320568D01*
X-101868Y-320652D01*
G01X-97085Y-324402D02*
X-97718Y-323568D01*
X-98035Y-322735D01*
Y-319402D01*
X-97718Y-318568D01*
X-97085Y-317735D01*
G01X-91668D02*
X-92175Y-317902D01*
X-92555Y-318318D01*
X-92808Y-318818D01*
X-92998Y-319485D01*
X-93061Y-320235D01*
X-92998Y-320985D01*
X-92808Y-321652D01*
X-92555Y-322152D01*
X-92175Y-322568D01*
X-91668Y-322735D01*
X-91161Y-322568D01*
X-90781Y-322152D01*
X-90528Y-321652D01*
X-90338Y-320985D01*
X-90275Y-320235D01*
X-90338Y-319485D01*
X-90528Y-318818D01*
X-90781Y-318318D01*
X-91161Y-317902D01*
X-91668Y-317735D01*
G01X-87961Y-321735D02*
X-87581Y-322318D01*
X-87075Y-322652D01*
X-86505Y-322735D01*
X-85998Y-322652D01*
X-85491Y-322235D01*
X-85175Y-321735D01*
X-85111Y-321235D01*
X-85238Y-320652D01*
X-85681Y-320235D01*
X-86125Y-320068D01*
X-86695D01*
G01X-86125D02*
X-85745Y-319818D01*
X-85428Y-319402D01*
X-85301Y-318902D01*
X-85428Y-318402D01*
X-85745Y-317985D01*
X-86315Y-317735D01*
X-86885Y-317818D01*
X-87455Y-318152D01*
G01X-81151Y-324402D02*
X-80518Y-323568D01*
X-80201Y-322735D01*
Y-319402D01*
X-80518Y-318568D01*
X-81151Y-317735D01*
G01X-77761Y-321735D02*
X-77381Y-322318D01*
X-76875Y-322652D01*
X-76305Y-322735D01*
X-75798Y-322652D01*
X-75291Y-322235D01*
X-74975Y-321735D01*
X-74911Y-321235D01*
X-75038Y-320652D01*
X-75481Y-320235D01*
X-75925Y-320068D01*
X-76495D01*
G01X-75925D02*
X-75545Y-319818D01*
X-75228Y-319402D01*
X-75101Y-318902D01*
X-75228Y-318402D01*
X-75545Y-317985D01*
X-76115Y-317735D01*
X-76685Y-317818D01*
X-77255Y-318152D01*
G01X-72471Y-318568D02*
X-72091Y-318068D01*
X-71648Y-317818D01*
X-71141Y-317735D01*
X-70508Y-317902D01*
X-70065Y-318318D01*
X-69938Y-318818D01*
X-70001Y-319318D01*
X-70255Y-319735D01*
X-71521Y-320568D01*
X-72091Y-321152D01*
X-72471Y-321985D01*
X-72598Y-322735D01*
X-69938D01*
G01X-66295D02*
X-66168Y-321652D01*
X-65978Y-320735D01*
X-65725Y-319902D01*
X-65408Y-318985D01*
X-64901Y-317735D01*
X-67435D01*
G01X-61891Y-321068D02*
X-60245D01*
G01X-57171Y-318568D02*
X-56791Y-318068D01*
X-56348Y-317818D01*
X-55841Y-317735D01*
X-55208Y-317902D01*
X-54765Y-318318D01*
X-54638Y-318818D01*
X-54701Y-319318D01*
X-54955Y-319735D01*
X-56221Y-320568D01*
X-56791Y-321152D01*
X-57171Y-321985D01*
X-57298Y-322735D01*
X-54638D01*
G01X-52261Y-321735D02*
X-51881Y-322318D01*
X-51375Y-322652D01*
X-50805Y-322735D01*
X-50298Y-322652D01*
X-49791Y-322235D01*
X-49475Y-321735D01*
X-49411Y-321235D01*
X-49538Y-320652D01*
X-49981Y-320235D01*
X-50425Y-320068D01*
X-50995D01*
G01X-50425D02*
X-50045Y-319818D01*
X-49728Y-319402D01*
X-49601Y-318902D01*
X-49728Y-318402D01*
X-50045Y-317985D01*
X-50615Y-317735D01*
X-51185Y-317818D01*
X-51755Y-318152D01*
G01X-45008Y-322735D02*
Y-317735D01*
X-47351Y-321318D01*
X-44185D01*
G01X-42061Y-321985D02*
X-41681Y-322402D01*
X-41238Y-322652D01*
X-40668Y-322735D01*
X-40098Y-322568D01*
X-39655Y-322235D01*
X-39338Y-321652D01*
X-39275Y-320985D01*
X-39401Y-320318D01*
X-39718Y-319902D01*
X-40161Y-319568D01*
X-40605Y-319485D01*
X-41048Y-319568D01*
X-41618Y-319902D01*
X-41428Y-317735D01*
X-39718D01*
G01X-31671Y-322735D02*
Y-317735D01*
X-29265D01*
G01X-30151Y-320152D02*
X-31671D01*
G01X-26951Y-322735D02*
X-25368Y-317735D01*
X-23785Y-322735D01*
G01X-24355Y-320985D02*
X-26381D01*
G01X-21598Y-322735D02*
X-18938Y-317735D01*
G01X-21598D02*
X-18938Y-322735D01*
G01X-15168Y-322902D02*
X-15295Y-322818D01*
Y-322652D01*
X-15168Y-322568D01*
X-15041Y-322652D01*
Y-322818D01*
X-15168Y-322902D01*
G01Y-320652D02*
X-15295Y-320568D01*
Y-320402D01*
X-15168Y-320318D01*
X-15041Y-320402D01*
Y-320568D01*
X-15168Y-320652D01*
G01X-10385Y-324402D02*
X-11018Y-323568D01*
X-11335Y-322735D01*
Y-319402D01*
X-11018Y-318568D01*
X-10385Y-317735D01*
G01X-4968D02*
X-5475Y-317902D01*
X-5855Y-318318D01*
X-6108Y-318818D01*
X-6298Y-319485D01*
X-6361Y-320235D01*
X-6298Y-320985D01*
X-6108Y-321652D01*
X-5855Y-322152D01*
X-5475Y-322568D01*
X-4968Y-322735D01*
X-4461Y-322568D01*
X-4081Y-322152D01*
X-3828Y-321652D01*
X-3638Y-320985D01*
X-3575Y-320235D01*
X-3638Y-319485D01*
X-3828Y-318818D01*
X-4081Y-318318D01*
X-4461Y-317902D01*
X-4968Y-317735D01*
G01X-1261Y-321735D02*
X-881Y-322318D01*
X-375Y-322652D01*
X195Y-322735D01*
X702Y-322652D01*
X1209Y-322235D01*
X1525Y-321735D01*
X1589Y-321235D01*
X1462Y-320652D01*
X1019Y-320235D01*
X575Y-320068D01*
X5D01*
G01X575D02*
X955Y-319818D01*
X1272Y-319402D01*
X1399Y-318902D01*
X1272Y-318402D01*
X955Y-317985D01*
X385Y-317735D01*
X-185Y-317818D01*
X-755Y-318152D01*
G01X5549Y-324402D02*
X6182Y-323568D01*
X6499Y-322735D01*
Y-319402D01*
X6182Y-318568D01*
X5549Y-317735D01*
G01X8939Y-321735D02*
X9319Y-322318D01*
X9825Y-322652D01*
X10395Y-322735D01*
X10902Y-322652D01*
X11409Y-322235D01*
X11725Y-321735D01*
X11789Y-321235D01*
X11662Y-320652D01*
X11219Y-320235D01*
X10775Y-320068D01*
X10205D01*
G01X10775D02*
X11155Y-319818D01*
X11472Y-319402D01*
X11599Y-318902D01*
X11472Y-318402D01*
X11155Y-317985D01*
X10585Y-317735D01*
X10015Y-317818D01*
X9445Y-318152D01*
G01X14355Y-322152D02*
X14799Y-322568D01*
X15305Y-322735D01*
X15812Y-322568D01*
X16255Y-322068D01*
X16572Y-321318D01*
X16699Y-320568D01*
Y-319652D01*
X16572Y-318902D01*
X16255Y-318235D01*
X15875Y-317902D01*
X15432Y-317735D01*
X14925Y-317902D01*
X14545Y-318235D01*
X14292Y-318735D01*
X14165Y-319402D01*
X14292Y-319985D01*
X14609Y-320568D01*
X14989Y-320902D01*
X15432Y-320985D01*
X15939Y-320818D01*
X16319Y-320402D01*
X16699Y-319652D01*
G01X20405Y-322735D02*
X20532Y-321652D01*
X20722Y-320735D01*
X20975Y-319902D01*
X21292Y-318985D01*
X21799Y-317735D01*
X19265D01*
G01X24809Y-321068D02*
X26455D01*
G01X29339Y-321735D02*
X29719Y-322318D01*
X30225Y-322652D01*
X30795Y-322735D01*
X31302Y-322652D01*
X31809Y-322235D01*
X32125Y-321735D01*
X32189Y-321235D01*
X32062Y-320652D01*
X31619Y-320235D01*
X31175Y-320068D01*
X30605D01*
G01X31175D02*
X31555Y-319818D01*
X31872Y-319402D01*
X31999Y-318902D01*
X31872Y-318402D01*
X31555Y-317985D01*
X30985Y-317735D01*
X30415Y-317818D01*
X29845Y-318152D01*
G01X34629Y-320652D02*
X35072Y-320068D01*
X35452Y-319735D01*
X35959Y-319568D01*
X36402Y-319735D01*
X36719Y-320068D01*
X36972Y-320568D01*
X37035Y-321152D01*
X36972Y-321652D01*
X36719Y-322152D01*
X36339Y-322568D01*
X35895Y-322735D01*
X35389Y-322568D01*
X34945Y-322068D01*
X34692Y-321318D01*
X34629Y-320485D01*
X34755Y-319402D01*
X34945Y-318818D01*
X35262Y-318235D01*
X35705Y-317818D01*
X36149Y-317735D01*
X36592Y-317902D01*
X36909Y-318318D01*
G01X40932Y-322735D02*
Y-317735D01*
X40172Y-318735D01*
G01Y-322735D02*
X41692D01*
G01X46792D02*
Y-317735D01*
X44449Y-321318D01*
X47615D01*
G01X-129168Y-252735D02*
Y-327735D01*
X370832D01*
Y-252735D01*
X-129168D01*
G01X65832D02*
Y-327735D01*
G01Y-302735D02*
X168832D01*
Y-277735D01*
G01X65832D02*
X168832D01*
G01X176339Y-312735D02*
Y-307735D01*
X177605D01*
X178112Y-307985D01*
X178492Y-308318D01*
X178809Y-308818D01*
X179062Y-309402D01*
X179125Y-310235D01*
X179062Y-311068D01*
X178809Y-311652D01*
X178492Y-312152D01*
X178112Y-312485D01*
X177605Y-312735D01*
X176339D01*
G01X181249D02*
X182832Y-307735D01*
X184415Y-312735D01*
G01X183845Y-310985D02*
X181819D01*
G01X187932Y-307735D02*
Y-312735D01*
G01X186475Y-307735D02*
X189389D01*
G01X194299Y-312735D02*
X191765D01*
Y-307735D01*
X194299D01*
G01X193285Y-310152D02*
X191765D01*
G01X198132Y-312902D02*
X198005Y-312818D01*
Y-312652D01*
X198132Y-312568D01*
X198259Y-312652D01*
Y-312818D01*
X198132Y-312902D01*
G01Y-310652D02*
X198005Y-310568D01*
Y-310402D01*
X198132Y-310318D01*
X198259Y-310402D01*
Y-310568D01*
X198132Y-310652D01*
G01X170832Y-252735D02*
Y-327735D01*
G01X168832Y-252735D02*
Y-327735D01*
G01X170832Y-302735D02*
X370832D01*
G01X176465Y-287735D02*
Y-282735D01*
X177985D01*
X178492Y-282985D01*
X178872Y-283568D01*
X178999Y-284235D01*
X178872Y-284902D01*
X178555Y-285402D01*
X177985Y-285652D01*
X176465D01*
G01X181692Y-287902D02*
X183972Y-282735D01*
G01X186475Y-287735D02*
Y-282735D01*
X189389Y-287735D01*
Y-282735D01*
G01X193032Y-287902D02*
X192905Y-287818D01*
Y-287652D01*
X193032Y-287568D01*
X193159Y-287652D01*
Y-287818D01*
X193032Y-287902D01*
G01Y-285652D02*
X192905Y-285568D01*
Y-285402D01*
X193032Y-285318D01*
X193159Y-285402D01*
Y-285568D01*
X193032Y-285652D01*
G01X170832Y-277735D02*
X370832D01*
G01X176465Y-262735D02*
Y-257735D01*
X177985D01*
X178492Y-257985D01*
X178872Y-258568D01*
X178999Y-259235D01*
X178872Y-259902D01*
X178555Y-260402D01*
X177985Y-260652D01*
X176465D01*
G01X181565Y-262735D02*
Y-257735D01*
X183149D01*
X183655Y-257985D01*
X183972Y-258318D01*
X184099Y-258985D01*
X183972Y-259652D01*
X183592Y-260068D01*
X183149Y-260318D01*
X181565D01*
G01X183149D02*
X184099Y-262735D01*
G01X187932D02*
X187425Y-262652D01*
X186982Y-262318D01*
X186602Y-261818D01*
X186349Y-261235D01*
X186222Y-260568D01*
Y-259902D01*
X186349Y-259235D01*
X186602Y-258652D01*
X186982Y-258152D01*
X187425Y-257818D01*
X187932Y-257735D01*
X188439Y-257818D01*
X188882Y-258152D01*
X189262Y-258652D01*
X189515Y-259235D01*
X189642Y-259902D01*
Y-260568D01*
X189515Y-261235D01*
X189262Y-261818D01*
X188882Y-262318D01*
X188439Y-262652D01*
X187932Y-262735D01*
G01X191765Y-261735D02*
X192082Y-262235D01*
X192462Y-262568D01*
X192905Y-262735D01*
X193412Y-262568D01*
X193792Y-262235D01*
X194172Y-261735D01*
X194299Y-261068D01*
Y-257735D01*
G01X199399Y-262735D02*
X196865D01*
Y-257735D01*
X199399D01*
G01X198385Y-260152D02*
X196865D01*
G01X204625Y-258152D02*
X204245Y-257902D01*
X203802Y-257735D01*
X203295D01*
X202725Y-257985D01*
X202282Y-258402D01*
X201965Y-258902D01*
X201712Y-259735D01*
X201649Y-260485D01*
X201775Y-261235D01*
X201965Y-261735D01*
X202345Y-262235D01*
X202789Y-262568D01*
X203232Y-262735D01*
X203675D01*
X204119Y-262568D01*
X204499Y-262318D01*
X204815Y-261985D01*
G01X208332Y-257735D02*
Y-262735D01*
G01X206875Y-257735D02*
X209789D01*
G01X213432Y-262902D02*
X213305Y-262818D01*
Y-262652D01*
X213432Y-262568D01*
X213559Y-262652D01*
Y-262818D01*
X213432Y-262902D01*
G01Y-260652D02*
X213305Y-260568D01*
Y-260402D01*
X213432Y-260318D01*
X213559Y-260402D01*
Y-260568D01*
X213432Y-260652D01*
G01X283832Y-302735D02*
Y-327735D01*
G01X288465Y-305235D02*
Y-310235D01*
X290999D01*
G01X294072Y-305235D02*
X295592D01*
G01X294832D02*
Y-310235D01*
G01X294072D02*
X295592D01*
G01X300439Y-307568D02*
X300692Y-307318D01*
X300882Y-306902D01*
X301009Y-306318D01*
X300882Y-305818D01*
X300629Y-305485D01*
X300185Y-305235D01*
X298475D01*
Y-310235D01*
X300565D01*
X301009Y-309902D01*
X301262Y-309402D01*
X301389Y-308818D01*
X301262Y-308235D01*
X300882Y-307735D01*
X300439Y-307568D01*
X298475D01*
G01X305032Y-310402D02*
X304905Y-310318D01*
Y-310152D01*
X305032Y-310068D01*
X305159Y-310152D01*
Y-310318D01*
X305032Y-310402D01*
G01Y-308152D02*
X304905Y-308068D01*
Y-307902D01*
X305032Y-307818D01*
X305159Y-307902D01*
Y-308068D01*
X305032Y-308152D01*
G01X328832Y-302735D02*
Y-327735D01*
G01X332732Y-305235D02*
Y-310235D01*
G01X331275Y-305235D02*
X334189D01*
G01X337832Y-310235D02*
X337452Y-310152D01*
X337072Y-309818D01*
X336819Y-309235D01*
X336692Y-308568D01*
X336819Y-307902D01*
X337072Y-307318D01*
X337452Y-306985D01*
X337832Y-306902D01*
X338212Y-306985D01*
X338592Y-307318D01*
X338845Y-307902D01*
X338909Y-308568D01*
X338845Y-309235D01*
X338592Y-309818D01*
X338212Y-310152D01*
X337832Y-310235D01*
G01X342932D02*
X342552Y-310152D01*
X342172Y-309818D01*
X341919Y-309235D01*
X341792Y-308568D01*
X341919Y-307902D01*
X342172Y-307318D01*
X342552Y-306985D01*
X342932Y-306902D01*
X343312Y-306985D01*
X343692Y-307318D01*
X343945Y-307902D01*
X344009Y-308568D01*
X343945Y-309235D01*
X343692Y-309818D01*
X343312Y-310152D01*
X342932Y-310235D01*
G01X348032D02*
Y-305235D01*
G01X353132Y-310402D02*
X353005Y-310318D01*
Y-310152D01*
X353132Y-310068D01*
X353259Y-310152D01*
Y-310318D01*
X353132Y-310402D01*
G01Y-308152D02*
X353005Y-308068D01*
Y-307902D01*
X353132Y-307818D01*
X353259Y-307902D01*
Y-308068D01*
X353132Y-308152D01*
G01X328832Y-277735D02*
Y-302735D01*
G01X331465Y-285235D02*
Y-280235D01*
X333049D01*
X333555Y-280485D01*
X333872Y-280818D01*
X333999Y-281485D01*
X333872Y-282152D01*
X333492Y-282568D01*
X333049Y-282818D01*
X331465D01*
G01X333049D02*
X333999Y-285235D01*
G01X339099D02*
X336565D01*
Y-280235D01*
X339099D01*
G01X338085Y-282652D02*
X336565D01*
G01X341349Y-280235D02*
X342932Y-285235D01*
X344515Y-280235D01*
G01X348032Y-285402D02*
X347905Y-285318D01*
Y-285152D01*
X348032Y-285068D01*
X348159Y-285152D01*
Y-285318D01*
X348032Y-285402D01*
G01Y-283152D02*
X347905Y-283068D01*
Y-282902D01*
X348032Y-282818D01*
X348159Y-282902D01*
Y-283068D01*
X348032Y-283152D01*
G01X351592Y-329435D02*
X351672Y-329360D01*
X351732Y-329235D01*
X351772Y-329060D01*
X351732Y-328910D01*
X351652Y-328810D01*
X351512Y-328735D01*
X350972D01*
Y-330235D01*
X351632D01*
X351772Y-330135D01*
X351852Y-329985D01*
X351892Y-329810D01*
X351852Y-329635D01*
X351732Y-329485D01*
X351592Y-329435D01*
X350972D01*
G01X352992Y-330235D02*
Y-329235D01*
G01Y-329410D02*
X352912Y-329310D01*
X352792Y-329260D01*
X352652Y-329235D01*
X352512Y-329285D01*
X352392Y-329385D01*
X352312Y-329535D01*
X352272Y-329735D01*
X352312Y-329935D01*
X352392Y-330085D01*
X352512Y-330185D01*
X352652Y-330235D01*
X352792Y-330210D01*
X352912Y-330135D01*
X352992Y-330035D01*
G01X353532Y-330060D02*
X353632Y-330160D01*
X353772Y-330235D01*
X353892D01*
X354012Y-330185D01*
X354092Y-330110D01*
X354132Y-330010D01*
X354112Y-329860D01*
X354032Y-329785D01*
X353672Y-329635D01*
X353592Y-329460D01*
X353632Y-329335D01*
X353712Y-329260D01*
X353832Y-329235D01*
X353952Y-329260D01*
X354072Y-329335D01*
G01X354732Y-329560D02*
X355372D01*
X355312Y-329385D01*
X355212Y-329285D01*
X355072Y-329235D01*
X354932Y-329260D01*
X354812Y-329335D01*
X354732Y-329510D01*
X354692Y-329660D01*
Y-329810D01*
X354732Y-329960D01*
X354832Y-330110D01*
X354952Y-330210D01*
X355092Y-330235D01*
X355232Y-330185D01*
X355372Y-330035D01*
G01X355872Y-330235D02*
Y-328735D01*
G01Y-329485D02*
X355972Y-329335D01*
X356092Y-329260D01*
X356212Y-329235D01*
X356392Y-329285D01*
X356512Y-329385D01*
X356592Y-329560D01*
Y-329760D01*
X356552Y-329960D01*
X356472Y-330110D01*
X356332Y-330210D01*
X356212Y-330235D01*
X356092Y-330210D01*
X355972Y-330135D01*
X355872Y-330010D01*
G01X357432Y-330235D02*
X357312Y-330210D01*
X357192Y-330110D01*
X357112Y-329935D01*
X357072Y-329735D01*
X357112Y-329535D01*
X357192Y-329360D01*
X357312Y-329260D01*
X357432Y-329235D01*
X357552Y-329260D01*
X357672Y-329360D01*
X357752Y-329535D01*
X357772Y-329735D01*
X357752Y-329935D01*
X357672Y-330110D01*
X357552Y-330210D01*
X357432Y-330235D01*
G01X358992D02*
Y-329235D01*
G01Y-329410D02*
X358912Y-329310D01*
X358792Y-329260D01*
X358652Y-329235D01*
X358512Y-329285D01*
X358392Y-329385D01*
X358312Y-329535D01*
X358272Y-329735D01*
X358312Y-329935D01*
X358392Y-330085D01*
X358512Y-330185D01*
X358652Y-330235D01*
X358792Y-330210D01*
X358912Y-330135D01*
X358992Y-330035D01*
G01X359552Y-330235D02*
Y-329235D01*
G01Y-329435D02*
X359652Y-329335D01*
X359752Y-329260D01*
X359892Y-329235D01*
X359992Y-329260D01*
X360112Y-329335D01*
G01X361392Y-328735D02*
Y-330235D01*
G01Y-330010D02*
X361312Y-330135D01*
X361192Y-330210D01*
X361052Y-330235D01*
X360892Y-330185D01*
X360772Y-330060D01*
X360692Y-329910D01*
X360672Y-329735D01*
X360692Y-329560D01*
X360772Y-329410D01*
X360892Y-329285D01*
X361052Y-329235D01*
X361192Y-329260D01*
X361292Y-329310D01*
X361392Y-329410D01*
G01X363032Y-330235D02*
Y-328735D01*
X363532D01*
X363692Y-328810D01*
X363792Y-328910D01*
X363832Y-329110D01*
X363792Y-329310D01*
X363672Y-329435D01*
X363532Y-329510D01*
X363032D01*
G01X363532D02*
X363832Y-330235D01*
G01X364332Y-329560D02*
X364972D01*
X364912Y-329385D01*
X364812Y-329285D01*
X364672Y-329235D01*
X364532Y-329260D01*
X364412Y-329335D01*
X364332Y-329510D01*
X364292Y-329660D01*
Y-329810D01*
X364332Y-329960D01*
X364432Y-330110D01*
X364552Y-330210D01*
X364692Y-330235D01*
X364832Y-330185D01*
X364972Y-330035D01*
G01X365472Y-329235D02*
X365832Y-330235D01*
X366192Y-329235D01*
G01X367032Y-330285D02*
X366992Y-330260D01*
Y-330210D01*
X367032Y-330185D01*
X367072Y-330210D01*
Y-330260D01*
X367032Y-330285D01*
G01X368192Y-330235D02*
X368232Y-329910D01*
X368292Y-329635D01*
X368372Y-329385D01*
X368472Y-329110D01*
X368632Y-328735D01*
X367832D01*
G01X369592Y-329435D02*
X369672Y-329360D01*
X369732Y-329235D01*
X369772Y-329060D01*
X369732Y-328910D01*
X369652Y-328810D01*
X369512Y-328735D01*
X368972D01*
Y-330235D01*
X369632D01*
X369772Y-330135D01*
X369852Y-329985D01*
X369892Y-329810D01*
X369852Y-329635D01*
X369732Y-329485D01*
X369592Y-329435D01*
X368972D01*
G01X-247901Y-428634D02*
Y1008173D01*
X2091018D01*
Y-428634D01*
X-247901D01*
G01X-115095Y-307460D02*
X-115565Y-307145D01*
X-116113Y-306935D01*
X-116740D01*
X-117445Y-307250D01*
X-117993Y-307775D01*
X-118385Y-308405D01*
X-118698Y-309455D01*
X-118776Y-310400D01*
X-118620Y-311345D01*
X-118385Y-311975D01*
X-117915Y-312605D01*
X-117366Y-313025D01*
X-116818Y-313235D01*
X-116270D01*
X-115721Y-313025D01*
X-115251Y-312710D01*
X-114860Y-312290D01*
G01X-111458Y-306935D02*
X-109578D01*
G01X-110518D02*
Y-313235D01*
G01X-111458D02*
X-109578D01*
G01X-104218Y-306935D02*
Y-313235D01*
G01X-106020Y-306935D02*
X-102416D01*
G01X-97918Y-313235D02*
Y-310400D01*
X-99485Y-306935D01*
G01X-96351D02*
X-97918Y-310400D01*
G01X-87041Y-311975D02*
X-86571Y-312710D01*
X-85945Y-313130D01*
X-85240Y-313235D01*
X-84613Y-313130D01*
X-83986Y-312605D01*
X-83595Y-311975D01*
X-83516Y-311345D01*
X-83673Y-310610D01*
X-84221Y-310085D01*
X-84770Y-309875D01*
X-85475D01*
G01X-84770D02*
X-84300Y-309560D01*
X-83908Y-309035D01*
X-83751Y-308405D01*
X-83908Y-307775D01*
X-84300Y-307250D01*
X-85005Y-306935D01*
X-85710Y-307040D01*
X-86415Y-307460D01*
G01X-80741Y-311975D02*
X-80271Y-312710D01*
X-79645Y-313130D01*
X-78940Y-313235D01*
X-78313Y-313130D01*
X-77686Y-312605D01*
X-77295Y-311975D01*
X-77216Y-311345D01*
X-77373Y-310610D01*
X-77921Y-310085D01*
X-78470Y-309875D01*
X-79175D01*
G01X-78470D02*
X-78000Y-309560D01*
X-77608Y-309035D01*
X-77451Y-308405D01*
X-77608Y-307775D01*
X-78000Y-307250D01*
X-78705Y-306935D01*
X-79410Y-307040D01*
X-80115Y-307460D01*
G01X-74441Y-311975D02*
X-73971Y-312710D01*
X-73345Y-313130D01*
X-72640Y-313235D01*
X-72013Y-313130D01*
X-71386Y-312605D01*
X-70995Y-311975D01*
X-70916Y-311345D01*
X-71073Y-310610D01*
X-71621Y-310085D01*
X-72170Y-309875D01*
X-72875D01*
G01X-72170D02*
X-71700Y-309560D01*
X-71308Y-309035D01*
X-71151Y-308405D01*
X-71308Y-307775D01*
X-71700Y-307250D01*
X-72405Y-306935D01*
X-73110Y-307040D01*
X-73815Y-307460D01*
G01X-66575Y-313235D02*
X-66418Y-311870D01*
X-66183Y-310715D01*
X-65870Y-309665D01*
X-65478Y-308510D01*
X-64851Y-306935D01*
X-67985D01*
G01X-60275Y-313235D02*
X-60118Y-311870D01*
X-59883Y-310715D01*
X-59570Y-309665D01*
X-59178Y-308510D01*
X-58551Y-306935D01*
X-61685D01*
G01X-53975Y-314390D02*
X-53661Y-313025D01*
G01X-47518Y-306935D02*
Y-313235D01*
G01X-49320Y-306935D02*
X-45716D01*
G01X-43176Y-313235D02*
X-41218Y-306935D01*
X-39260Y-313235D01*
G01X-39965Y-311030D02*
X-42471D01*
G01X-35858Y-306935D02*
X-33978D01*
G01X-34918D02*
Y-313235D01*
G01X-35858D02*
X-33978D01*
G01X-30968Y-306935D02*
X-29871Y-313235D01*
X-28618Y-306935D01*
X-27365Y-313235D01*
X-26268Y-306935D01*
G01X-24276Y-313235D02*
X-22318Y-306935D01*
X-20360Y-313235D01*
G01X-21065Y-311030D02*
X-23571D01*
G01X-17820Y-313235D02*
Y-306935D01*
X-14216Y-313235D01*
Y-306935D01*
G01X-3810Y-315335D02*
X-4593Y-314285D01*
X-4985Y-313235D01*
Y-309035D01*
X-4593Y-307985D01*
X-3810Y-306935D01*
G01X7615Y-313235D02*
Y-306935D01*
X9574D01*
X10200Y-307250D01*
X10592Y-307670D01*
X10749Y-308510D01*
X10592Y-309350D01*
X10122Y-309875D01*
X9574Y-310190D01*
X7615D01*
G01X9574D02*
X10749Y-313235D01*
G01X15482Y-313445D02*
X15325Y-313340D01*
Y-313130D01*
X15482Y-313025D01*
X15639Y-313130D01*
Y-313340D01*
X15482Y-313445D01*
G01X21782Y-313235D02*
X21155Y-313130D01*
X20607Y-312710D01*
X20137Y-312080D01*
X19824Y-311345D01*
X19667Y-310505D01*
Y-309665D01*
X19824Y-308825D01*
X20137Y-308090D01*
X20607Y-307460D01*
X21155Y-307040D01*
X21782Y-306935D01*
X22409Y-307040D01*
X22957Y-307460D01*
X23427Y-308090D01*
X23740Y-308825D01*
X23897Y-309665D01*
Y-310505D01*
X23740Y-311345D01*
X23427Y-312080D01*
X22957Y-312710D01*
X22409Y-313130D01*
X21782Y-313235D01*
G01X28082Y-313445D02*
X27925Y-313340D01*
Y-313130D01*
X28082Y-313025D01*
X28239Y-313130D01*
Y-313340D01*
X28082Y-313445D01*
G01X36105Y-307460D02*
X35635Y-307145D01*
X35087Y-306935D01*
X34460D01*
X33755Y-307250D01*
X33207Y-307775D01*
X32815Y-308405D01*
X32502Y-309455D01*
X32424Y-310400D01*
X32580Y-311345D01*
X32815Y-311975D01*
X33285Y-312605D01*
X33834Y-313025D01*
X34382Y-313235D01*
X34930D01*
X35479Y-313025D01*
X35949Y-312710D01*
X36340Y-312290D01*
G01X40682Y-313445D02*
X40525Y-313340D01*
Y-313130D01*
X40682Y-313025D01*
X40839Y-313130D01*
Y-313340D01*
X40682Y-313445D01*
G01X47374Y-315335D02*
X48157Y-314285D01*
X48549Y-313235D01*
Y-309035D01*
X48157Y-307985D01*
X47374Y-306935D01*
G01X-118620Y-293235D02*
Y-286935D01*
X-115016Y-293235D01*
Y-286935D01*
G01X-110518Y-293235D02*
X-111145Y-293130D01*
X-111693Y-292710D01*
X-112163Y-292080D01*
X-112476Y-291345D01*
X-112633Y-290505D01*
Y-289665D01*
X-112476Y-288825D01*
X-112163Y-288090D01*
X-111693Y-287460D01*
X-111145Y-287040D01*
X-110518Y-286935D01*
X-109891Y-287040D01*
X-109343Y-287460D01*
X-108873Y-288090D01*
X-108560Y-288825D01*
X-108403Y-289665D01*
Y-290505D01*
X-108560Y-291345D01*
X-108873Y-292080D01*
X-109343Y-292710D01*
X-109891Y-293130D01*
X-110518Y-293235D01*
G01X-104218Y-293445D02*
X-104375Y-293340D01*
Y-293130D01*
X-104218Y-293025D01*
X-104061Y-293130D01*
Y-293340D01*
X-104218Y-293445D01*
G01X-99406Y-287985D02*
X-98936Y-287355D01*
X-98388Y-287040D01*
X-97761Y-286935D01*
X-96978Y-287145D01*
X-96430Y-287670D01*
X-96273Y-288300D01*
X-96351Y-288930D01*
X-96665Y-289455D01*
X-98231Y-290505D01*
X-98936Y-291240D01*
X-99406Y-292290D01*
X-99563Y-293235D01*
X-96273D01*
G01X-91618D02*
Y-286935D01*
X-92558Y-288195D01*
G01Y-293235D02*
X-90678D01*
G01X-85318D02*
Y-286935D01*
X-86258Y-288195D01*
G01Y-293235D02*
X-84378D01*
G01X-79175Y-294390D02*
X-78861Y-293025D01*
G01X-75068Y-286935D02*
X-73971Y-293235D01*
X-72718Y-286935D01*
X-71465Y-293235D01*
X-70368Y-286935D01*
G01X-64851Y-293235D02*
X-67985D01*
Y-286935D01*
X-64851D01*
G01X-66105Y-289980D02*
X-67985D01*
G01X-61920Y-293235D02*
Y-286935D01*
X-58316Y-293235D01*
Y-286935D01*
G01X-55463Y-293235D02*
Y-286935D01*
G01X-52173D02*
Y-293235D01*
G01Y-290085D02*
X-55463D01*
G01X-49241Y-286935D02*
Y-291450D01*
X-48928Y-292395D01*
X-48301Y-293025D01*
X-47518Y-293235D01*
X-46735Y-293025D01*
X-46108Y-292395D01*
X-45795Y-291450D01*
Y-286935D01*
G01X-43176Y-293235D02*
X-41218Y-286935D01*
X-39260Y-293235D01*
G01X-39965Y-291030D02*
X-42471D01*
G01X-30106Y-287985D02*
X-29636Y-287355D01*
X-29088Y-287040D01*
X-28461Y-286935D01*
X-27678Y-287145D01*
X-27130Y-287670D01*
X-26973Y-288300D01*
X-27051Y-288930D01*
X-27365Y-289455D01*
X-28931Y-290505D01*
X-29636Y-291240D01*
X-30106Y-292290D01*
X-30263Y-293235D01*
X-26973D01*
G01X-24120D02*
Y-286935D01*
X-20516Y-293235D01*
Y-286935D01*
G01X-17741Y-293235D02*
Y-286935D01*
X-16175D01*
X-15548Y-287250D01*
X-15078Y-287670D01*
X-14686Y-288300D01*
X-14373Y-289035D01*
X-14295Y-290085D01*
X-14373Y-291135D01*
X-14686Y-291870D01*
X-15078Y-292500D01*
X-15548Y-292920D01*
X-16175Y-293235D01*
X-17741D01*
G01X-4985D02*
Y-286935D01*
X-3026D01*
X-2400Y-287250D01*
X-2008Y-287670D01*
X-1851Y-288510D01*
X-2008Y-289350D01*
X-2478Y-289875D01*
X-3026Y-290190D01*
X-4985D01*
G01X-3026D02*
X-1851Y-293235D01*
G01X1159D02*
Y-286935D01*
X2725D01*
X3352Y-287250D01*
X3822Y-287670D01*
X4214Y-288300D01*
X4527Y-289035D01*
X4605Y-290085D01*
X4527Y-291135D01*
X4214Y-291870D01*
X3822Y-292500D01*
X3352Y-292920D01*
X2725Y-293235D01*
X1159D01*
G01X9182Y-293445D02*
X9025Y-293340D01*
Y-293130D01*
X9182Y-293025D01*
X9339Y-293130D01*
Y-293340D01*
X9182Y-293445D01*
G01X-116348Y-300085D02*
X-114781D01*
Y-301975D01*
X-115251Y-302605D01*
X-115800Y-303025D01*
X-116583Y-303235D01*
X-117366Y-303025D01*
X-117915Y-302605D01*
X-118385Y-301975D01*
X-118698Y-301240D01*
X-118855Y-300400D01*
Y-299665D01*
X-118698Y-299035D01*
X-118385Y-298300D01*
X-117915Y-297670D01*
X-117445Y-297250D01*
X-116818Y-296935D01*
X-116270D01*
X-115643Y-297145D01*
X-115173Y-297565D01*
G01X-112241Y-296935D02*
Y-301450D01*
X-111928Y-302395D01*
X-111301Y-303025D01*
X-110518Y-303235D01*
X-109735Y-303025D01*
X-109108Y-302395D01*
X-108795Y-301450D01*
Y-296935D01*
G01X-105158D02*
X-103278D01*
G01X-104218D02*
Y-303235D01*
G01X-105158D02*
X-103278D01*
G01X-99563Y-302395D02*
X-98936Y-302920D01*
X-98231Y-303235D01*
X-97605D01*
X-96978Y-302920D01*
X-96508Y-302395D01*
X-96273Y-301660D01*
X-96430Y-300925D01*
X-96821Y-300295D01*
X-97526Y-299875D01*
X-98466Y-299665D01*
X-99015Y-299245D01*
X-99250Y-298510D01*
X-99093Y-297775D01*
X-98701Y-297250D01*
X-98153Y-296935D01*
X-97605D01*
X-97056Y-297145D01*
X-96586Y-297670D01*
G01X-93263Y-303235D02*
Y-296935D01*
G01X-89973D02*
Y-303235D01*
G01Y-300085D02*
X-93263D01*
G01X-87276Y-303235D02*
X-85318Y-296935D01*
X-83360Y-303235D01*
G01X-84065Y-301030D02*
X-86571D01*
G01X-80820Y-303235D02*
Y-296935D01*
X-77216Y-303235D01*
Y-296935D01*
G01X-68141Y-303235D02*
Y-296935D01*
X-66575D01*
X-65948Y-297250D01*
X-65478Y-297670D01*
X-65086Y-298300D01*
X-64773Y-299035D01*
X-64695Y-300085D01*
X-64773Y-301135D01*
X-65086Y-301870D01*
X-65478Y-302500D01*
X-65948Y-302920D01*
X-66575Y-303235D01*
X-68141D01*
G01X-61058Y-296935D02*
X-59178D01*
G01X-60118D02*
Y-303235D01*
G01X-61058D02*
X-59178D01*
G01X-55463Y-302395D02*
X-54836Y-302920D01*
X-54131Y-303235D01*
X-53505D01*
X-52878Y-302920D01*
X-52408Y-302395D01*
X-52173Y-301660D01*
X-52330Y-300925D01*
X-52721Y-300295D01*
X-53426Y-299875D01*
X-54366Y-299665D01*
X-54915Y-299245D01*
X-55150Y-298510D01*
X-54993Y-297775D01*
X-54601Y-297250D01*
X-54053Y-296935D01*
X-53505D01*
X-52956Y-297145D01*
X-52486Y-297670D01*
G01X-47518Y-296935D02*
Y-303235D01*
G01X-49320Y-296935D02*
X-45716D01*
G01X-41218Y-303445D02*
X-41375Y-303340D01*
Y-303130D01*
X-41218Y-303025D01*
X-41061Y-303130D01*
Y-303340D01*
X-41218Y-303445D01*
G01X-35075Y-304390D02*
X-34761Y-303025D01*
G01X-28618Y-296935D02*
Y-303235D01*
G01X-30420Y-296935D02*
X-26816D01*
G01X-24276Y-303235D02*
X-22318Y-296935D01*
X-20360Y-303235D01*
G01X-21065Y-301030D02*
X-23571D01*
G01X-16018Y-303235D02*
X-16645Y-303130D01*
X-17193Y-302710D01*
X-17663Y-302080D01*
X-17976Y-301345D01*
X-18133Y-300505D01*
Y-299665D01*
X-17976Y-298825D01*
X-17663Y-298090D01*
X-17193Y-297460D01*
X-16645Y-297040D01*
X-16018Y-296935D01*
X-15391Y-297040D01*
X-14843Y-297460D01*
X-14373Y-298090D01*
X-14060Y-298825D01*
X-13903Y-299665D01*
Y-300505D01*
X-14060Y-301345D01*
X-14373Y-302080D01*
X-14843Y-302710D01*
X-15391Y-303130D01*
X-16018Y-303235D01*
G01X-9718D02*
Y-300400D01*
X-11285Y-296935D01*
G01X-8151D02*
X-9718Y-300400D01*
G01X-5141Y-296935D02*
Y-301450D01*
X-4828Y-302395D01*
X-4201Y-303025D01*
X-3418Y-303235D01*
X-2635Y-303025D01*
X-2008Y-302395D01*
X-1695Y-301450D01*
Y-296935D01*
G01X924Y-303235D02*
X2882Y-296935D01*
X4840Y-303235D01*
G01X4135Y-301030D02*
X1629D01*
G01X7380Y-303235D02*
Y-296935D01*
X10984Y-303235D01*
Y-296935D01*
G01X-94518Y-282535D02*
X-97038Y-282118D01*
X-99243Y-280452D01*
X-101133Y-277952D01*
X-102393Y-275035D01*
X-103023Y-271702D01*
Y-268368D01*
X-102393Y-265035D01*
X-101133Y-262118D01*
X-99243Y-259619D01*
X-97038Y-257952D01*
X-94518Y-257535D01*
X-91998Y-257952D01*
X-89793Y-259619D01*
X-87903Y-262118D01*
X-86643Y-265035D01*
X-86013Y-268368D01*
Y-271702D01*
X-86643Y-275035D01*
X-87903Y-277952D01*
X-89793Y-280452D01*
X-91998Y-282118D01*
X-94518Y-282535D01*
G01X-91998Y-275868D02*
X-88218Y-282535D01*
G01X-74673Y-265869D02*
Y-277535D01*
X-73413Y-280452D01*
X-71523Y-282118D01*
X-69318Y-282535D01*
X-67113Y-282118D01*
X-65223Y-280452D01*
X-63963Y-277535D01*
G01Y-282535D02*
Y-265869D01*
G01X-38448Y-282535D02*
Y-265869D01*
G01Y-268785D02*
X-39708Y-267119D01*
X-41598Y-266285D01*
X-43803Y-265869D01*
X-46008Y-266702D01*
X-47898Y-268368D01*
X-49158Y-270869D01*
X-49788Y-274202D01*
X-49158Y-277535D01*
X-47898Y-280036D01*
X-46008Y-281702D01*
X-43803Y-282535D01*
X-41598Y-282118D01*
X-39708Y-280869D01*
X-38448Y-279202D01*
G01X-24273Y-282535D02*
Y-265869D01*
G01Y-270035D02*
X-23013Y-267952D01*
X-21123Y-266285D01*
X-18603Y-265869D01*
X-16398Y-266285D01*
X-14508Y-267952D01*
X-13563Y-270869D01*
Y-282535D01*
G01X6282Y-257535D02*
Y-282535D01*
G01X1872Y-265869D02*
X10692D01*
G01X37152Y-282535D02*
Y-265869D01*
G01Y-268785D02*
X35892Y-267119D01*
X34002Y-266285D01*
X31797Y-265869D01*
X29592Y-266702D01*
X27702Y-268368D01*
X26442Y-270869D01*
X25812Y-274202D01*
X26442Y-277535D01*
X27702Y-280036D01*
X29592Y-281702D01*
X31797Y-282535D01*
X34002Y-282118D01*
X35892Y-280869D01*
X37152Y-279202D01*
G01X76832Y-262235D02*
Y-270235D01*
X80832D01*
G01X88632D02*
Y-264902D01*
G01Y-265835D02*
X88232Y-265302D01*
X87632Y-265035D01*
X86932Y-264902D01*
X86232Y-265168D01*
X85632Y-265702D01*
X85232Y-266502D01*
X85032Y-267568D01*
X85232Y-268635D01*
X85632Y-269435D01*
X86232Y-269968D01*
X86932Y-270235D01*
X87632Y-270102D01*
X88232Y-269702D01*
X88632Y-269169D01*
G01X92732Y-272635D02*
X93332Y-272902D01*
X94132Y-272635D01*
X94632Y-272102D01*
X95032Y-271435D01*
X95632Y-269302D01*
X96932Y-264902D01*
G01X93732D02*
X95632Y-269302D01*
G01X101332Y-266635D02*
X104532D01*
X104232Y-265702D01*
X103732Y-265168D01*
X103032Y-264902D01*
X102332Y-265035D01*
X101732Y-265435D01*
X101332Y-266368D01*
X101132Y-267169D01*
Y-267968D01*
X101332Y-268768D01*
X101832Y-269568D01*
X102432Y-270102D01*
X103132Y-270235D01*
X103832Y-269968D01*
X104532Y-269169D01*
G01X109432Y-270235D02*
Y-264902D01*
G01Y-265968D02*
X109932Y-265435D01*
X110432Y-265035D01*
X111132Y-264902D01*
X111632Y-265035D01*
X112232Y-265435D01*
G01X95532Y-320235D02*
Y-312235D01*
X100132Y-320235D01*
Y-312235D01*
G01X105832Y-314902D02*
Y-320235D01*
G01Y-312768D02*
X105632Y-312635D01*
Y-312368D01*
X105832Y-312235D01*
X106032Y-312368D01*
Y-312635D01*
X105832Y-312768D01*
G01X112132Y-320235D02*
Y-314902D01*
G01Y-316235D02*
X112532Y-315568D01*
X113132Y-315035D01*
X113932Y-314902D01*
X114632Y-315035D01*
X115232Y-315568D01*
X115532Y-316502D01*
Y-320235D01*
G01X123632D02*
Y-314902D01*
G01Y-315835D02*
X123232Y-315302D01*
X122632Y-315035D01*
X121932Y-314902D01*
X121232Y-315168D01*
X120632Y-315702D01*
X120232Y-316502D01*
X120032Y-317568D01*
X120232Y-318635D01*
X120632Y-319435D01*
X121232Y-319968D01*
X121932Y-320235D01*
X122632Y-320102D01*
X123232Y-319702D01*
X123632Y-319169D01*
G01X101132Y-290968D02*
X101532Y-290568D01*
X101832Y-289902D01*
X102032Y-288968D01*
X101832Y-288168D01*
X101432Y-287635D01*
X100732Y-287235D01*
X98032D01*
Y-295235D01*
X101332D01*
X102032Y-294702D01*
X102432Y-293902D01*
X102632Y-292968D01*
X102432Y-292035D01*
X101832Y-291235D01*
X101132Y-290968D01*
X98032D01*
G01X108332Y-295235D02*
X107532Y-295102D01*
X106832Y-294568D01*
X106232Y-293768D01*
X105832Y-292835D01*
X105632Y-291768D01*
Y-290702D01*
X105832Y-289635D01*
X106232Y-288702D01*
X106832Y-287902D01*
X107532Y-287368D01*
X108332Y-287235D01*
X109132Y-287368D01*
X109832Y-287902D01*
X110432Y-288702D01*
X110832Y-289635D01*
X111032Y-290702D01*
Y-291768D01*
X110832Y-292835D01*
X110432Y-293768D01*
X109832Y-294568D01*
X109132Y-295102D01*
X108332Y-295235D01*
G01X116332Y-287235D02*
Y-295235D01*
G01X114032Y-287235D02*
X118632D01*
G01X124332D02*
Y-295235D01*
G01X122032Y-287235D02*
X126632D01*
G01X132332Y-295235D02*
X131532Y-295102D01*
X130832Y-294568D01*
X130232Y-293768D01*
X129832Y-292835D01*
X129632Y-291768D01*
Y-290702D01*
X129832Y-289635D01*
X130232Y-288702D01*
X130832Y-287902D01*
X131532Y-287368D01*
X132332Y-287235D01*
X133132Y-287368D01*
X133832Y-287902D01*
X134432Y-288702D01*
X134832Y-289635D01*
X135032Y-290702D01*
Y-291768D01*
X134832Y-292835D01*
X134432Y-293768D01*
X133832Y-294568D01*
X133132Y-295102D01*
X132332Y-295235D01*
G01X137732D02*
Y-287235D01*
X140332Y-293902D01*
X142932Y-287235D01*
Y-295235D01*
G01X131532Y-270235D02*
Y-262235D01*
X127832Y-267968D01*
X132832D01*
G01X203432Y-313568D02*
X204032Y-312768D01*
X204732Y-312368D01*
X205532Y-312235D01*
X206532Y-312502D01*
X207232Y-313168D01*
X207432Y-313968D01*
X207332Y-314769D01*
X206932Y-315435D01*
X204932Y-316768D01*
X204032Y-317702D01*
X203432Y-319035D01*
X203232Y-320235D01*
X207432D01*
G01X213332Y-312235D02*
X212532Y-312502D01*
X211932Y-313168D01*
X211532Y-313968D01*
X211232Y-315035D01*
X211132Y-316235D01*
X211232Y-317435D01*
X211532Y-318502D01*
X211932Y-319302D01*
X212532Y-319968D01*
X213332Y-320235D01*
X214132Y-319968D01*
X214732Y-319302D01*
X215132Y-318502D01*
X215432Y-317435D01*
X215532Y-316235D01*
X215432Y-315035D01*
X215132Y-313968D01*
X214732Y-313168D01*
X214132Y-312502D01*
X213332Y-312235D01*
G01X219432Y-313568D02*
X220032Y-312768D01*
X220732Y-312368D01*
X221532Y-312235D01*
X222532Y-312502D01*
X223232Y-313168D01*
X223432Y-313968D01*
X223332Y-314769D01*
X222932Y-315435D01*
X220932Y-316768D01*
X220032Y-317702D01*
X219432Y-319035D01*
X219232Y-320235D01*
X223432D01*
G01X227432Y-313568D02*
X228032Y-312768D01*
X228732Y-312368D01*
X229532Y-312235D01*
X230532Y-312502D01*
X231232Y-313168D01*
X231432Y-313968D01*
X231332Y-314769D01*
X230932Y-315435D01*
X228932Y-316768D01*
X228032Y-317702D01*
X227432Y-319035D01*
X227232Y-320235D01*
X231432D01*
G01X235532Y-320502D02*
X239132Y-312235D01*
G01X245332Y-320235D02*
Y-312235D01*
X244132Y-313835D01*
G01Y-320235D02*
X246532D01*
G01X251432Y-313568D02*
X252032Y-312768D01*
X252732Y-312368D01*
X253532Y-312235D01*
X254532Y-312502D01*
X255232Y-313168D01*
X255432Y-313968D01*
X255332Y-314769D01*
X254932Y-315435D01*
X252932Y-316768D01*
X252032Y-317702D01*
X251432Y-319035D01*
X251232Y-320235D01*
X255432D01*
G01X259532Y-320502D02*
X263132Y-312235D01*
G01X269332D02*
X268532Y-312502D01*
X267932Y-313168D01*
X267532Y-313968D01*
X267232Y-315035D01*
X267132Y-316235D01*
X267232Y-317435D01*
X267532Y-318502D01*
X267932Y-319302D01*
X268532Y-319968D01*
X269332Y-320235D01*
X270132Y-319968D01*
X270732Y-319302D01*
X271132Y-318502D01*
X271432Y-317435D01*
X271532Y-316235D01*
X271432Y-315035D01*
X271132Y-313968D01*
X270732Y-313168D01*
X270132Y-312502D01*
X269332Y-312235D01*
G01X275632Y-319302D02*
X276332Y-319968D01*
X277132Y-320235D01*
X277932Y-319968D01*
X278632Y-319169D01*
X279132Y-317968D01*
X279332Y-316768D01*
Y-315302D01*
X279132Y-314102D01*
X278632Y-313035D01*
X278032Y-312502D01*
X277332Y-312235D01*
X276532Y-312502D01*
X275932Y-313035D01*
X275532Y-313835D01*
X275332Y-314902D01*
X275532Y-315835D01*
X276032Y-316768D01*
X276632Y-317302D01*
X277332Y-317435D01*
X278132Y-317169D01*
X278732Y-316502D01*
X279332Y-315302D01*
G01X205632Y-295235D02*
Y-287235D01*
X207632D01*
X208432Y-287635D01*
X209032Y-288168D01*
X209532Y-288968D01*
X209932Y-289902D01*
X210032Y-291235D01*
X209932Y-292568D01*
X209532Y-293502D01*
X209032Y-294302D01*
X208432Y-294835D01*
X207632Y-295235D01*
X205632D01*
G01X213332D02*
X215832Y-287235D01*
X218332Y-295235D01*
G01X217432Y-292435D02*
X214232D01*
G01X223832Y-287235D02*
X223032Y-287502D01*
X222432Y-288168D01*
X222032Y-288968D01*
X221732Y-290035D01*
X221632Y-291235D01*
X221732Y-292435D01*
X222032Y-293502D01*
X222432Y-294302D01*
X223032Y-294968D01*
X223832Y-295235D01*
X224632Y-294968D01*
X225232Y-294302D01*
X225632Y-293502D01*
X225932Y-292435D01*
X226032Y-291235D01*
X225932Y-290035D01*
X225632Y-288968D01*
X225232Y-288168D01*
X224632Y-287502D01*
X223832Y-287235D01*
G01X229932Y-295235D02*
Y-287235D01*
X233732D01*
G01X232332Y-291102D02*
X229932D01*
G01X239832Y-287235D02*
X239032Y-287502D01*
X238432Y-288168D01*
X238032Y-288968D01*
X237732Y-290035D01*
X237632Y-291235D01*
X237732Y-292435D01*
X238032Y-293502D01*
X238432Y-294302D01*
X239032Y-294968D01*
X239832Y-295235D01*
X240632Y-294968D01*
X241232Y-294302D01*
X241632Y-293502D01*
X241932Y-292435D01*
X242032Y-291235D01*
X241932Y-290035D01*
X241632Y-288968D01*
X241232Y-288168D01*
X240632Y-287502D01*
X239832Y-287235D01*
G01X247832D02*
Y-295235D01*
G01X245532Y-287235D02*
X250132D01*
G01X255832Y-295235D02*
Y-291635D01*
X253832Y-287235D01*
G01X257832D02*
X255832Y-291635D01*
G01X264632Y-290968D02*
X265032Y-290568D01*
X265332Y-289902D01*
X265532Y-288968D01*
X265332Y-288168D01*
X264932Y-287635D01*
X264232Y-287235D01*
X261532D01*
Y-295235D01*
X264832D01*
X265532Y-294702D01*
X265932Y-293902D01*
X266132Y-292968D01*
X265932Y-292035D01*
X265332Y-291235D01*
X264632Y-290968D01*
X261532D01*
G01X273032Y-295235D02*
Y-287235D01*
X269332Y-292968D01*
X274332D01*
G01X277632Y-295235D02*
Y-287235D01*
X279632D01*
X280432Y-287635D01*
X281032Y-288168D01*
X281532Y-288968D01*
X281932Y-289902D01*
X282032Y-291235D01*
X281932Y-292568D01*
X281532Y-293502D01*
X281032Y-294302D01*
X280432Y-294835D01*
X279632Y-295235D01*
X277632D01*
G01X287832Y-287235D02*
X287032Y-287502D01*
X286432Y-288168D01*
X286032Y-288968D01*
X285732Y-290035D01*
X285632Y-291235D01*
X285732Y-292435D01*
X286032Y-293502D01*
X286432Y-294302D01*
X287032Y-294968D01*
X287832Y-295235D01*
X288632Y-294968D01*
X289232Y-294302D01*
X289632Y-293502D01*
X289932Y-292435D01*
X290032Y-291235D01*
X289932Y-290035D01*
X289632Y-288968D01*
X289232Y-288168D01*
X288632Y-287502D01*
X287832Y-287235D01*
G01X233432Y-270235D02*
Y-262235D01*
X237232D01*
G01X235832Y-266102D02*
X233432D01*
G01X243332Y-262235D02*
X242532Y-262502D01*
X241932Y-263168D01*
X241532Y-263968D01*
X241232Y-265035D01*
X241132Y-266235D01*
X241232Y-267435D01*
X241532Y-268502D01*
X241932Y-269302D01*
X242532Y-269968D01*
X243332Y-270235D01*
X244132Y-269968D01*
X244732Y-269302D01*
X245132Y-268502D01*
X245432Y-267435D01*
X245532Y-266235D01*
X245432Y-265035D01*
X245132Y-263968D01*
X244732Y-263168D01*
X244132Y-262502D01*
X243332Y-262235D01*
G01X251332D02*
Y-270235D01*
G01X249032Y-262235D02*
X253632D01*
G01X256332Y-272902D02*
X262332D01*
G01X265332Y-270235D02*
Y-262235D01*
X267732D01*
X268532Y-262635D01*
X269132Y-263568D01*
X269332Y-264635D01*
X269132Y-265702D01*
X268632Y-266502D01*
X267732Y-266902D01*
X265332D01*
G01X272832Y-270235D02*
X275332Y-262235D01*
X277832Y-270235D01*
G01X276932Y-267435D02*
X273732D01*
G01X281032Y-270235D02*
Y-262235D01*
X285632Y-270235D01*
Y-262235D01*
G01X293332Y-270235D02*
X289332D01*
Y-262235D01*
X293332D01*
G01X291732Y-266102D02*
X289332D01*
G01X297332Y-262235D02*
Y-270235D01*
X301332D01*
G01X304332Y-272902D02*
X310332D01*
G01X316132Y-265968D02*
X316532Y-265568D01*
X316832Y-264902D01*
X317032Y-263968D01*
X316832Y-263168D01*
X316432Y-262635D01*
X315732Y-262235D01*
X313032D01*
Y-270235D01*
X316332D01*
X317032Y-269702D01*
X317432Y-268902D01*
X317632Y-267968D01*
X317432Y-267035D01*
X316832Y-266235D01*
X316132Y-265968D01*
X313032D01*
G01X321132Y-270235D02*
Y-262235D01*
X323132D01*
X323932Y-262635D01*
X324532Y-263168D01*
X325032Y-263968D01*
X325432Y-264902D01*
X325532Y-266235D01*
X325432Y-267568D01*
X325032Y-268502D01*
X324532Y-269302D01*
X323932Y-269835D01*
X323132Y-270235D01*
X321132D01*
G01X291832Y-323235D02*
Y-315235D01*
X290632Y-316835D01*
G01Y-323235D02*
X293032D01*
G01X297932Y-319902D02*
X298632Y-318968D01*
X299232Y-318435D01*
X300032Y-318168D01*
X300732Y-318435D01*
X301232Y-318968D01*
X301632Y-319768D01*
X301732Y-320702D01*
X301632Y-321502D01*
X301232Y-322302D01*
X300632Y-322968D01*
X299932Y-323235D01*
X299132Y-322968D01*
X298432Y-322169D01*
X298032Y-320968D01*
X297932Y-319635D01*
X298132Y-317902D01*
X298432Y-316968D01*
X298932Y-316035D01*
X299632Y-315368D01*
X300332Y-315235D01*
X301032Y-315502D01*
X301532Y-316168D01*
G01X307832Y-323502D02*
X307632Y-323368D01*
Y-323102D01*
X307832Y-322968D01*
X308032Y-323102D01*
Y-323368D01*
X307832Y-323502D01*
G01X313932Y-319902D02*
X314632Y-318968D01*
X315232Y-318435D01*
X316032Y-318168D01*
X316732Y-318435D01*
X317232Y-318968D01*
X317632Y-319768D01*
X317732Y-320702D01*
X317632Y-321502D01*
X317232Y-322302D01*
X316632Y-322968D01*
X315932Y-323235D01*
X315132Y-322968D01*
X314432Y-322169D01*
X314032Y-320968D01*
X313932Y-319635D01*
X314132Y-317902D01*
X314432Y-316968D01*
X314932Y-316035D01*
X315632Y-315368D01*
X316332Y-315235D01*
X317032Y-315502D01*
X317532Y-316168D01*
G01X336832Y-323235D02*
Y-315235D01*
X335632Y-316835D01*
G01Y-323235D02*
X338032D01*
G01X344632D02*
X344832Y-321502D01*
X345132Y-320035D01*
X345532Y-318702D01*
X346032Y-317235D01*
X346832Y-315235D01*
X342832D01*
G01X352832Y-323502D02*
X352632Y-323368D01*
Y-323102D01*
X352832Y-322968D01*
X353032Y-323102D01*
Y-323368D01*
X352832Y-323502D01*
G01X358932Y-316568D02*
X359532Y-315768D01*
X360232Y-315368D01*
X361032Y-315235D01*
X362032Y-315502D01*
X362732Y-316168D01*
X362932Y-316968D01*
X362832Y-317769D01*
X362432Y-318435D01*
X360432Y-319768D01*
X359532Y-320702D01*
X358932Y-322035D01*
X358732Y-323235D01*
X362932D01*
G01X356632Y-298235D02*
Y-290235D01*
X358632D01*
X359432Y-290635D01*
X360032Y-291168D01*
X360532Y-291968D01*
X360932Y-292902D01*
X361032Y-294235D01*
X360932Y-295568D01*
X360532Y-296502D01*
X360032Y-297302D01*
X359432Y-297835D01*
X358632Y-298235D01*
X356632D01*
G54D12*
X10315Y20079D03*
X33937D03*
G54D21*
X61516Y326772D03*
Y314961D03*
X110532Y326772D03*
Y314961D03*
G54D31*
G01X20315Y20079D02*
X41255Y28755D01*
X46500Y34000D01*
Y82400D01*
X42400Y86500D01*
G01X77480Y26299D02*
Y51342D01*
X74822Y54000D01*
X68720D01*
G01X111965Y11716D02*
X107856D01*
X79020Y40552D01*
Y51980D01*
X74683Y56317D01*
X67183D01*
X62043Y61457D01*
Y70543D01*
X65000Y73500D01*
G01X84500Y76500D02*
Y74000D01*
X77500Y67000D01*
X68000D01*
X64500Y63500D01*
G01X66925Y70000D02*
X77001D01*
X81729Y74728D01*
Y77772D01*
G01X73000Y91000D02*
X68500Y95500D01*
Y119000D01*
X76000Y126500D01*
G01X59500Y95000D02*
Y114462D01*
X74538Y129500D01*
X83500D01*
G01X76000Y123000D02*
X70840Y117840D01*
Y97160D01*
X73000Y95000D01*
G01X59500Y117960D02*
X74540Y133000D01*
X83500D01*
G01X88500Y123500D02*
Y132456D01*
X84956Y136000D01*
X78340D01*
G01X66500Y181500D02*
X82016Y197016D01*
Y235484D01*
X78000Y239500D01*
X76500D01*
G01X66500Y185500D02*
X79676Y198676D01*
Y233824D01*
X78000Y235500D01*
X76500D01*
G01X81000Y95000D02*
X83500Y92500D01*
Y84810D01*
X89942Y78368D01*
Y62462D01*
X91425Y60979D01*
Y37457D01*
X106954Y21928D01*
Y21716D01*
G01X81000Y91000D02*
Y84000D01*
X87472Y77528D01*
Y64992D01*
X83808Y61328D01*
Y39074D01*
X106166Y16716D01*
X109812D01*
G01X127500Y6716D02*
X98181Y36035D01*
Y53948D01*
X100100Y55867D01*
X107666D01*
X109325Y57526D01*
Y71283D01*
X130042Y92000D01*
X137000D01*
G01X92500Y126000D02*
Y131200D01*
X84965Y138735D01*
X80310D01*
G01X132000Y10500D02*
X130382D01*
X110190Y30692D01*
Y40190D01*
X112565Y42565D01*
Y69637D01*
X127428Y84500D01*
X137000D01*
G01X139500Y10500D02*
X137000Y8000D01*
X129882D01*
X105181Y32701D01*
Y50961D01*
X110962Y56742D01*
Y70212D01*
X128750Y88000D01*
X137000D01*
G01X101969Y68228D02*
Y64785D01*
X103578Y63176D01*
X107318D01*
G01X349937Y104912D02*
Y122440D01*
X350677Y123180D01*
X356441D01*
X357181Y123920D01*
Y125580D01*
X356441Y126320D01*
X343774D01*
X343034Y127060D01*
Y128720D01*
X343774Y129460D01*
X356100D01*
X356840Y130200D01*
Y131860D01*
X356100Y132600D01*
X343774D01*
X343034Y133340D01*
Y135000D01*
X343774Y135740D01*
X356100D01*
X356840Y136480D01*
Y138140D01*
X356100Y138880D01*
X343774D01*
X343034Y139620D01*
Y141280D01*
X343774Y142020D01*
X356100D01*
X356840Y142760D01*
Y144420D01*
X356100Y145160D01*
X343774D01*
X343034Y145900D01*
Y147560D01*
X343774Y148300D01*
X356100D01*
X356840Y149040D01*
Y150700D01*
X356100Y151440D01*
X343774D01*
X343034Y152180D01*
Y153840D01*
X343774Y154580D01*
X356100D01*
X356840Y155320D01*
Y156980D01*
X356100Y157720D01*
X343774D01*
X343034Y158460D01*
Y160120D01*
X343774Y160860D01*
X356100D01*
X356840Y161600D01*
Y163260D01*
X356100Y164000D01*
X343774D01*
X343034Y164740D01*
Y166400D01*
X343774Y167140D01*
X356100D01*
X356840Y167880D01*
Y169540D01*
X356100Y170280D01*
X343774D01*
X343034Y171020D01*
Y172680D01*
X343774Y173420D01*
X356100D01*
X356840Y174160D01*
Y175820D01*
X356100Y176560D01*
X343774D01*
X343034Y177300D01*
Y178960D01*
X343774Y179700D01*
X356100D01*
X356840Y180440D01*
Y182100D01*
X356100Y182840D01*
X343774D01*
X343034Y183580D01*
Y185240D01*
X343774Y185980D01*
X356100D01*
X356840Y186720D01*
Y188380D01*
X356100Y189120D01*
X343774D01*
X343034Y189860D01*
Y191520D01*
X343774Y192260D01*
X356100D01*
X356840Y193000D01*
Y194660D01*
X356100Y195400D01*
X343774D01*
X343034Y196140D01*
Y197800D01*
X343774Y198540D01*
X356100D01*
X356840Y199280D01*
Y200940D01*
X356100Y201680D01*
X343774D01*
X343034Y202420D01*
Y204080D01*
X343774Y204820D01*
X356407D01*
X357147Y205560D01*
Y207220D01*
X356407Y207960D01*
X343774D01*
X343034Y208700D01*
Y210360D01*
X343774Y211100D01*
X349197D01*
X349937Y211840D01*
Y218371D01*
X349254Y219054D01*
X340677D01*
X339937Y218314D01*
Y104912D01*
G54D13*
X13553Y48198D03*
Y69124D03*
X9218Y58661D03*
X34479Y48198D03*
X24016Y43863D03*
X34479Y69124D03*
X24016Y73459D03*
X38814Y58661D03*
X118671Y237080D03*
Y258006D03*
X114336Y247543D03*
X139597Y237080D03*
X129134Y232745D03*
Y262341D03*
X139597Y258006D03*
X143932Y247543D03*
G54D22*
X87756Y47244D03*
X109095Y89370D03*
G54D14*
X8000Y99500D03*
Y110500D03*
X16000Y109441D03*
X12500Y117000D03*
X11500Y200000D03*
Y192000D03*
Y184000D03*
X33000Y186000D03*
X19500Y221500D03*
Y213500D03*
X59586Y40000D03*
X59500Y55000D03*
X48941Y89500D03*
X52000Y81000D03*
X59500Y95000D03*
X54059Y102500D03*
X41500Y103500D03*
X41038Y112537D03*
X41000Y213532D03*
X59075Y204000D03*
X56500Y261000D03*
X55000Y276000D03*
X81000Y8000D03*
X72555Y46921D03*
X70075Y64500D03*
X68720Y54000D03*
X81729Y77772D03*
X64075Y200000D03*
X66500Y189500D03*
X68500Y231500D03*
X69075Y247000D03*
X78937Y270653D03*
X75394Y288205D03*
X99500Y9000D03*
X91000Y18500D03*
X98000Y99000D03*
X93111Y288205D03*
X86024Y270653D03*
X93111D03*
X84843Y288205D03*
X101500Y277500D03*
X118500Y6716D03*
X113181Y31701D03*
X106954Y21716D03*
X111965Y11716D03*
X109812Y16716D03*
X117000Y122500D03*
X132000Y10500D03*
X139500D03*
X127500Y6716D03*
X134500Y105000D03*
Y119000D03*
X140000Y177500D03*
X132500Y185000D03*
X140000D03*
X132500Y192500D03*
X140000D03*
X132500Y200000D03*
X140000D03*
Y215000D03*
X132500Y207500D03*
X140000D03*
X132500Y215000D03*
X148500Y84000D03*
X147500Y177500D03*
Y200000D03*
Y185000D03*
Y192500D03*
Y222500D03*
Y215000D03*
Y207500D03*
G54D23*
X101969Y52480D03*
Y68228D03*
Y60354D03*
X94882Y54449D03*
Y64291D03*
Y72165D03*
X101969Y83976D03*
Y76102D03*
G54D24*
X87756Y89370D03*
X109095Y47244D03*
G54D15*
X20315Y20079D03*
X43937D03*
G54D16*
X24016Y58661D03*
X129134Y247543D03*
G54D25*
X94882Y82008D03*
G54D17*
X25984Y279449D03*
X136221Y43425D03*
G54D26*
X339937Y104912D03*
X344937Y91728D03*
X349937Y104912D03*
X352033Y234525D03*
X342033D03*
X347033Y247709D03*
G54D18*
X57480Y26299D03*
X67480D03*
G54D27*
X350500Y420150D03*
X340500D03*
X350500Y445150D03*
X340500D03*
Y597350D03*
X350500D03*
X340500Y622350D03*
X350500D03*
X380000Y316336D03*
X370000D03*
X380000Y341336D03*
X370000D03*
Y597350D03*
X380000D03*
X370000Y622350D03*
X380000D03*
G54D28*
X370195Y93000D03*
X380195D03*
Y247618D03*
X370195D03*
G54D19*
X77480Y26299D03*
G54D29*
X370195Y83000D03*
X380195D03*
Y257618D03*
X370195D03*
M02*
